FILE_TYPE = MACRO_DRAWING;
SET COLOR_WIRE YELLOW;
SET COLOR_PROP ORANGE;
SET COLOR_DOT WHITE;
SET COLOR_ARC YELLOW;
SET COLOR_BODY GREEN;
SET COLOR_NOTE PURPLE;
SET PROP_DISPLAY VALUE;
SET PAGE_NUMBER P98;
FORCEADD OFFPAGE..5
(-8375 2075);
FORCEPROP 2 LAST $XR0 38 
J 0
(-8629 2075);
DISPLAY 0.638298 (-8629 2075);
PAINT MONO (-8629 2075);
FORCEPROP 2 LAST CDS_LIB mstr_standard
J 0
(-8375 2075);
DISPLAY 0.808511 (-8375 2075);
DISPLAY INVISIBLE (-8375 2075);
FORCEPROP 1 LAST OFFPAGE TRUE
J 0
(-8050 1950);
DISPLAY 0.872340 (-8050 1950);
PAINT GREEN (-8050 1950);
DISPLAY INVISIBLE (-8050 1950);
FORCEPROP 1 LAST COMMENT_BODY TRUE
J 0
(-8275 2000);
DISPLAY 0.872340 (-8275 2000);
PAINT GREEN (-8275 2000);
DISPLAY INVISIBLE (-8275 2000);
FORCEPROP 2 LAST PATH I1
J 0
(-8575 2125);
DISPLAY 1.021277 (-8575 2125);
DISPLAY INVISIBLE (-8575 2125);
FORCEADD OFFPAGE..1
(-8200 3225);
FORCEPROP 2 LAST $XR0 38 
J 0
(-8421 3225);
DISPLAY 0.638298 (-8421 3225);
PAINT MONO (-8421 3225);
FORCEPROP 2 LAST CDS_LIB mstr_standard
J 0
(-8200 3225);
DISPLAY 0.808511 (-8200 3225);
DISPLAY INVISIBLE (-8200 3225);
FORCEPROP 1 LAST OFFPAGE TRUE
J 0
(-7875 3100);
DISPLAY 0.872340 (-7875 3100);
PAINT GREEN (-7875 3100);
DISPLAY INVISIBLE (-7875 3100);
FORCEPROP 1 LAST COMMENT_BODY TRUE
J 0
(-8075 3125);
DISPLAY 0.872340 (-8075 3125);
PAINT GREEN (-8075 3125);
DISPLAY INVISIBLE (-8075 3125);
FORCEPROP 2 LAST PATH I10
J 0
(-8400 3275);
DISPLAY 1.021277 (-8400 3275);
DISPLAY INVISIBLE (-8400 3275);
FORCEADD TAP..1
(-6075 4325);
FORCEPROP 3 LASTPIN (-6125 4325) SIG_NAME M_B_CPU1_SA_DQ<7>
J 0
(-6115 4335);
DISPLAY 0.659574 (-6115 4335);
PAINT MONO (-6115 4335);
DISPLAY INVISIBLE (-6115 4335);
FORCEPROP 1 LASTPIN (-6125 4325) BN 7
J 0
(-6137 4333);
DISPLAY 0.489362 (-6137 4333);
PAINT GREEN (-6137 4333);
FORCEPROP 2 LAST CDS_LIB mstr_standard
J 0
(-6075 4325);
DISPLAY 0.723404 (-6075 4325);
PAINT MONO (-6075 4325);
DISPLAY INVISIBLE (-6075 4325);
FORCEPROP 1 LAST BODY_TYPE PLUMBING
J 0
(-6075 4375);
DISPLAY 0.872340 (-6075 4375);
PAINT GREEN (-6075 4375);
DISPLAY INVISIBLE (-6075 4375);
FORCEPROP 1 LAST HDL_TAP TRUE
J 0
(-5750 4200);
DISPLAY 0.872340 (-5750 4200);
DISPLAY INVISIBLE (-5750 4200);
FORCEPROP 1 LAST PATH I100
J 0
(-6077 4325);
DISPLAY 0.872340 (-6077 4325);
PAINT GREEN (-6077 4325);
DISPLAY INVISIBLE (-6077 4325);
FORCEADD TAP..1
(-6075 4575);
FORCEPROP 3 LASTPIN (-6125 4575) SIG_NAME M_B_CPU1_SA_DQ<12>
J 0
(-6115 4585);
DISPLAY 0.659574 (-6115 4585);
PAINT MONO (-6115 4585);
DISPLAY INVISIBLE (-6115 4585);
FORCEPROP 1 LASTPIN (-6125 4575) BN 12
J 0
(-6137 4583);
DISPLAY 0.489362 (-6137 4583);
PAINT GREEN (-6137 4583);
FORCEPROP 2 LAST CDS_LIB mstr_standard
J 0
(-6075 4575);
DISPLAY 0.723404 (-6075 4575);
PAINT MONO (-6075 4575);
DISPLAY INVISIBLE (-6075 4575);
FORCEPROP 1 LAST BODY_TYPE PLUMBING
J 0
(-6075 4625);
DISPLAY 0.872340 (-6075 4625);
PAINT GREEN (-6075 4625);
DISPLAY INVISIBLE (-6075 4625);
FORCEPROP 1 LAST HDL_TAP TRUE
J 0
(-5750 4450);
DISPLAY 0.872340 (-5750 4450);
DISPLAY INVISIBLE (-5750 4450);
FORCEPROP 1 LAST PATH I101
J 0
(-6077 4575);
DISPLAY 0.872340 (-6077 4575);
PAINT GREEN (-6077 4575);
DISPLAY INVISIBLE (-6077 4575);
FORCEADD TAP..1
(-6075 4525);
FORCEPROP 3 LASTPIN (-6125 4525) SIG_NAME M_B_CPU1_SA_DQ<11>
J 0
(-6115 4535);
DISPLAY 0.659574 (-6115 4535);
PAINT MONO (-6115 4535);
DISPLAY INVISIBLE (-6115 4535);
FORCEPROP 1 LASTPIN (-6125 4525) BN 11
J 0
(-6137 4533);
DISPLAY 0.489362 (-6137 4533);
PAINT GREEN (-6137 4533);
FORCEPROP 2 LAST CDS_LIB mstr_standard
J 0
(-6075 4525);
DISPLAY 0.723404 (-6075 4525);
PAINT MONO (-6075 4525);
DISPLAY INVISIBLE (-6075 4525);
FORCEPROP 1 LAST BODY_TYPE PLUMBING
J 0
(-6075 4575);
DISPLAY 0.872340 (-6075 4575);
PAINT GREEN (-6075 4575);
DISPLAY INVISIBLE (-6075 4575);
FORCEPROP 1 LAST HDL_TAP TRUE
J 0
(-5750 4400);
DISPLAY 0.872340 (-5750 4400);
DISPLAY INVISIBLE (-5750 4400);
FORCEPROP 1 LAST PATH I102
J 0
(-6077 4525);
DISPLAY 0.872340 (-6077 4525);
PAINT GREEN (-6077 4525);
DISPLAY INVISIBLE (-6077 4525);
FORCEADD TAP..1
(-6075 4475);
FORCEPROP 3 LASTPIN (-6125 4475) SIG_NAME M_B_CPU1_SA_DQ<10>
J 0
(-6115 4485);
DISPLAY 0.659574 (-6115 4485);
PAINT MONO (-6115 4485);
DISPLAY INVISIBLE (-6115 4485);
FORCEPROP 1 LASTPIN (-6125 4475) BN 10
J 0
(-6137 4483);
DISPLAY 0.489362 (-6137 4483);
PAINT GREEN (-6137 4483);
FORCEPROP 2 LAST CDS_LIB mstr_standard
J 0
(-6075 4475);
DISPLAY 0.723404 (-6075 4475);
PAINT MONO (-6075 4475);
DISPLAY INVISIBLE (-6075 4475);
FORCEPROP 1 LAST BODY_TYPE PLUMBING
J 0
(-6075 4525);
DISPLAY 0.872340 (-6075 4525);
PAINT GREEN (-6075 4525);
DISPLAY INVISIBLE (-6075 4525);
FORCEPROP 1 LAST HDL_TAP TRUE
J 0
(-5750 4350);
DISPLAY 0.872340 (-5750 4350);
DISPLAY INVISIBLE (-5750 4350);
FORCEPROP 1 LAST PATH I103
J 0
(-6077 4475);
DISPLAY 0.872340 (-6077 4475);
PAINT GREEN (-6077 4475);
DISPLAY INVISIBLE (-6077 4475);
FORCEADD TAP..1
(-6075 4425);
FORCEPROP 3 LASTPIN (-6125 4425) SIG_NAME M_B_CPU1_SA_DQ<9>
J 0
(-6115 4435);
DISPLAY 0.659574 (-6115 4435);
PAINT MONO (-6115 4435);
DISPLAY INVISIBLE (-6115 4435);
FORCEPROP 1 LASTPIN (-6125 4425) BN 9
J 0
(-6137 4433);
DISPLAY 0.489362 (-6137 4433);
PAINT GREEN (-6137 4433);
FORCEPROP 2 LAST CDS_LIB mstr_standard
J 0
(-6075 4425);
DISPLAY 0.723404 (-6075 4425);
PAINT MONO (-6075 4425);
DISPLAY INVISIBLE (-6075 4425);
FORCEPROP 1 LAST BODY_TYPE PLUMBING
J 0
(-6075 4475);
DISPLAY 0.872340 (-6075 4475);
PAINT GREEN (-6075 4475);
DISPLAY INVISIBLE (-6075 4475);
FORCEPROP 1 LAST HDL_TAP TRUE
J 0
(-5750 4300);
DISPLAY 0.872340 (-5750 4300);
DISPLAY INVISIBLE (-5750 4300);
FORCEPROP 1 LAST PATH I104
J 0
(-6077 4425);
DISPLAY 0.872340 (-6077 4425);
PAINT GREEN (-6077 4425);
DISPLAY INVISIBLE (-6077 4425);
FORCEADD TAP..1
(-6075 4375);
FORCEPROP 3 LASTPIN (-6125 4375) SIG_NAME M_B_CPU1_SA_DQ<8>
J 0
(-6115 4385);
DISPLAY 0.659574 (-6115 4385);
PAINT MONO (-6115 4385);
DISPLAY INVISIBLE (-6115 4385);
FORCEPROP 1 LASTPIN (-6125 4375) BN 8
J 0
(-6137 4383);
DISPLAY 0.489362 (-6137 4383);
PAINT GREEN (-6137 4383);
FORCEPROP 2 LAST CDS_LIB mstr_standard
J 0
(-6075 4375);
DISPLAY 0.723404 (-6075 4375);
PAINT MONO (-6075 4375);
DISPLAY INVISIBLE (-6075 4375);
FORCEPROP 1 LAST BODY_TYPE PLUMBING
J 0
(-6075 4425);
DISPLAY 0.872340 (-6075 4425);
PAINT GREEN (-6075 4425);
DISPLAY INVISIBLE (-6075 4425);
FORCEPROP 1 LAST HDL_TAP TRUE
J 0
(-5750 4250);
DISPLAY 0.872340 (-5750 4250);
DISPLAY INVISIBLE (-5750 4250);
FORCEPROP 1 LAST PATH I105
J 0
(-6077 4375);
DISPLAY 0.872340 (-6077 4375);
PAINT GREEN (-6077 4375);
DISPLAY INVISIBLE (-6077 4375);
FORCEADD TAP..1
(-6075 4825);
FORCEPROP 3 LASTPIN (-6125 4825) SIG_NAME M_B_CPU1_SA_DQ<17>
J 0
(-6115 4835);
DISPLAY 0.659574 (-6115 4835);
PAINT MONO (-6115 4835);
DISPLAY INVISIBLE (-6115 4835);
FORCEPROP 1 LASTPIN (-6125 4825) BN 17
J 0
(-6137 4833);
DISPLAY 0.489362 (-6137 4833);
PAINT GREEN (-6137 4833);
FORCEPROP 2 LAST CDS_LIB mstr_standard
J 0
(-6075 4825);
DISPLAY 0.723404 (-6075 4825);
PAINT MONO (-6075 4825);
DISPLAY INVISIBLE (-6075 4825);
FORCEPROP 1 LAST BODY_TYPE PLUMBING
J 0
(-6075 4875);
DISPLAY 0.872340 (-6075 4875);
PAINT GREEN (-6075 4875);
DISPLAY INVISIBLE (-6075 4875);
FORCEPROP 1 LAST HDL_TAP TRUE
J 0
(-5750 4700);
DISPLAY 0.872340 (-5750 4700);
DISPLAY INVISIBLE (-5750 4700);
FORCEPROP 1 LAST PATH I106
J 0
(-6077 4825);
DISPLAY 0.872340 (-6077 4825);
PAINT GREEN (-6077 4825);
DISPLAY INVISIBLE (-6077 4825);
FORCEADD TAP..1
(-6075 4775);
FORCEPROP 3 LASTPIN (-6125 4775) SIG_NAME M_B_CPU1_SA_DQ<16>
J 0
(-6115 4785);
DISPLAY 0.659574 (-6115 4785);
PAINT MONO (-6115 4785);
DISPLAY INVISIBLE (-6115 4785);
FORCEPROP 1 LASTPIN (-6125 4775) BN 16
J 0
(-6137 4783);
DISPLAY 0.489362 (-6137 4783);
PAINT GREEN (-6137 4783);
FORCEPROP 2 LAST CDS_LIB mstr_standard
J 0
(-6075 4775);
DISPLAY 0.723404 (-6075 4775);
PAINT MONO (-6075 4775);
DISPLAY INVISIBLE (-6075 4775);
FORCEPROP 1 LAST BODY_TYPE PLUMBING
J 0
(-6075 4825);
DISPLAY 0.872340 (-6075 4825);
PAINT GREEN (-6075 4825);
DISPLAY INVISIBLE (-6075 4825);
FORCEPROP 1 LAST HDL_TAP TRUE
J 0
(-5750 4650);
DISPLAY 0.872340 (-5750 4650);
DISPLAY INVISIBLE (-5750 4650);
FORCEPROP 1 LAST PATH I107
J 0
(-6077 4775);
DISPLAY 0.872340 (-6077 4775);
PAINT GREEN (-6077 4775);
DISPLAY INVISIBLE (-6077 4775);
FORCEADD TAP..1
(-6075 4625);
FORCEPROP 3 LASTPIN (-6125 4625) SIG_NAME M_B_CPU1_SA_DQ<13>
J 0
(-6115 4635);
DISPLAY 0.659574 (-6115 4635);
PAINT MONO (-6115 4635);
DISPLAY INVISIBLE (-6115 4635);
FORCEPROP 1 LASTPIN (-6125 4625) BN 13
J 0
(-6137 4633);
DISPLAY 0.489362 (-6137 4633);
PAINT GREEN (-6137 4633);
FORCEPROP 2 LAST CDS_LIB mstr_standard
J 0
(-6075 4625);
DISPLAY 0.723404 (-6075 4625);
PAINT MONO (-6075 4625);
DISPLAY INVISIBLE (-6075 4625);
FORCEPROP 1 LAST BODY_TYPE PLUMBING
J 0
(-6075 4675);
DISPLAY 0.872340 (-6075 4675);
PAINT GREEN (-6075 4675);
DISPLAY INVISIBLE (-6075 4675);
FORCEPROP 1 LAST HDL_TAP TRUE
J 0
(-5750 4500);
DISPLAY 0.872340 (-5750 4500);
DISPLAY INVISIBLE (-5750 4500);
FORCEPROP 1 LAST PATH I108
J 0
(-6077 4625);
DISPLAY 0.872340 (-6077 4625);
PAINT GREEN (-6077 4625);
DISPLAY INVISIBLE (-6077 4625);
FORCEADD TAP..1
(-6075 4725);
FORCEPROP 3 LASTPIN (-6125 4725) SIG_NAME M_B_CPU1_SA_DQ<15>
J 0
(-6115 4735);
DISPLAY 0.659574 (-6115 4735);
PAINT MONO (-6115 4735);
DISPLAY INVISIBLE (-6115 4735);
FORCEPROP 1 LASTPIN (-6125 4725) BN 15
J 0
(-6137 4733);
DISPLAY 0.489362 (-6137 4733);
PAINT GREEN (-6137 4733);
FORCEPROP 2 LAST CDS_LIB mstr_standard
J 0
(-6075 4725);
DISPLAY 0.723404 (-6075 4725);
PAINT MONO (-6075 4725);
DISPLAY INVISIBLE (-6075 4725);
FORCEPROP 1 LAST BODY_TYPE PLUMBING
J 0
(-6075 4775);
DISPLAY 0.872340 (-6075 4775);
PAINT GREEN (-6075 4775);
DISPLAY INVISIBLE (-6075 4775);
FORCEPROP 1 LAST HDL_TAP TRUE
J 0
(-5750 4600);
DISPLAY 0.872340 (-5750 4600);
DISPLAY INVISIBLE (-5750 4600);
FORCEPROP 1 LAST PATH I109
J 0
(-6077 4725);
DISPLAY 0.872340 (-6077 4725);
PAINT GREEN (-6077 4725);
DISPLAY INVISIBLE (-6077 4725);
FORCEADD OFFPAGE..1
(-8375 4675);
FORCEPROP 2 LAST $XR0 38 
J 0
(-8626 4675);
DISPLAY 0.638298 (-8626 4675);
PAINT MONO (-8626 4675);
FORCEPROP 2 LAST CDS_LIB mstr_standard
J 0
(-8375 4675);
DISPLAY 0.808511 (-8375 4675);
DISPLAY INVISIBLE (-8375 4675);
FORCEPROP 1 LAST OFFPAGE TRUE
J 0
(-8050 4550);
DISPLAY 0.872340 (-8050 4550);
PAINT GREEN (-8050 4550);
DISPLAY INVISIBLE (-8050 4550);
FORCEPROP 1 LAST COMMENT_BODY TRUE
J 0
(-8250 4575);
DISPLAY 0.872340 (-8250 4575);
PAINT GREEN (-8250 4575);
DISPLAY INVISIBLE (-8250 4575);
FORCEPROP 2 LAST PATH I11
J 0
(-8575 4725);
DISPLAY 1.021277 (-8575 4725);
DISPLAY INVISIBLE (-8575 4725);
FORCEADD TAP..1
(-6075 4675);
FORCEPROP 3 LASTPIN (-6125 4675) SIG_NAME M_B_CPU1_SA_DQ<14>
J 0
(-6115 4685);
DISPLAY 0.659574 (-6115 4685);
PAINT MONO (-6115 4685);
DISPLAY INVISIBLE (-6115 4685);
FORCEPROP 1 LASTPIN (-6125 4675) BN 14
J 0
(-6137 4683);
DISPLAY 0.489362 (-6137 4683);
PAINT GREEN (-6137 4683);
FORCEPROP 2 LAST CDS_LIB mstr_standard
J 0
(-6075 4675);
DISPLAY 0.723404 (-6075 4675);
PAINT MONO (-6075 4675);
DISPLAY INVISIBLE (-6075 4675);
FORCEPROP 1 LAST BODY_TYPE PLUMBING
J 0
(-6075 4725);
DISPLAY 0.872340 (-6075 4725);
PAINT GREEN (-6075 4725);
DISPLAY INVISIBLE (-6075 4725);
FORCEPROP 1 LAST HDL_TAP TRUE
J 0
(-5750 4550);
DISPLAY 0.872340 (-5750 4550);
DISPLAY INVISIBLE (-5750 4550);
FORCEPROP 1 LAST PATH I110
J 0
(-6077 4675);
DISPLAY 0.872340 (-6077 4675);
PAINT GREEN (-6077 4675);
DISPLAY INVISIBLE (-6077 4675);
FORCEADD TAP..1
(-6075 5025);
FORCEPROP 3 LASTPIN (-6125 5025) SIG_NAME M_B_CPU1_SA_DQ<21>
J 0
(-6115 5035);
DISPLAY 0.659574 (-6115 5035);
PAINT MONO (-6115 5035);
DISPLAY INVISIBLE (-6115 5035);
FORCEPROP 1 LASTPIN (-6125 5025) BN 21
J 0
(-6137 5033);
DISPLAY 0.489362 (-6137 5033);
PAINT GREEN (-6137 5033);
FORCEPROP 2 LAST CDS_LIB mstr_standard
J 0
(-6075 5025);
DISPLAY 0.723404 (-6075 5025);
PAINT MONO (-6075 5025);
DISPLAY INVISIBLE (-6075 5025);
FORCEPROP 1 LAST BODY_TYPE PLUMBING
J 0
(-6075 5075);
DISPLAY 0.872340 (-6075 5075);
PAINT GREEN (-6075 5075);
DISPLAY INVISIBLE (-6075 5075);
FORCEPROP 1 LAST HDL_TAP TRUE
J 0
(-5750 4900);
DISPLAY 0.872340 (-5750 4900);
DISPLAY INVISIBLE (-5750 4900);
FORCEPROP 1 LAST PATH I111
J 0
(-6077 5025);
DISPLAY 0.872340 (-6077 5025);
PAINT GREEN (-6077 5025);
DISPLAY INVISIBLE (-6077 5025);
FORCEADD TAP..1
(-6075 5075);
FORCEPROP 3 LASTPIN (-6125 5075) SIG_NAME M_B_CPU1_SA_DQ<22>
J 0
(-6115 5085);
DISPLAY 0.659574 (-6115 5085);
PAINT MONO (-6115 5085);
DISPLAY INVISIBLE (-6115 5085);
FORCEPROP 1 LASTPIN (-6125 5075) BN 22
J 0
(-6137 5083);
DISPLAY 0.489362 (-6137 5083);
PAINT GREEN (-6137 5083);
FORCEPROP 2 LAST CDS_LIB mstr_standard
J 0
(-6075 5075);
DISPLAY 0.723404 (-6075 5075);
PAINT MONO (-6075 5075);
DISPLAY INVISIBLE (-6075 5075);
FORCEPROP 1 LAST BODY_TYPE PLUMBING
J 0
(-6075 5125);
DISPLAY 0.872340 (-6075 5125);
PAINT GREEN (-6075 5125);
DISPLAY INVISIBLE (-6075 5125);
FORCEPROP 1 LAST HDL_TAP TRUE
J 0
(-5750 4950);
DISPLAY 0.872340 (-5750 4950);
DISPLAY INVISIBLE (-5750 4950);
FORCEPROP 1 LAST PATH I112
J 0
(-6077 5075);
DISPLAY 0.872340 (-6077 5075);
PAINT GREEN (-6077 5075);
DISPLAY INVISIBLE (-6077 5075);
FORCEADD TAP..1
(-6075 4925);
FORCEPROP 3 LASTPIN (-6125 4925) SIG_NAME M_B_CPU1_SA_DQ<19>
J 0
(-6115 4935);
DISPLAY 0.659574 (-6115 4935);
PAINT MONO (-6115 4935);
DISPLAY INVISIBLE (-6115 4935);
FORCEPROP 1 LASTPIN (-6125 4925) BN 19
J 0
(-6137 4933);
DISPLAY 0.489362 (-6137 4933);
PAINT GREEN (-6137 4933);
FORCEPROP 2 LAST CDS_LIB mstr_standard
J 0
(-6075 4925);
DISPLAY 0.723404 (-6075 4925);
PAINT MONO (-6075 4925);
DISPLAY INVISIBLE (-6075 4925);
FORCEPROP 1 LAST BODY_TYPE PLUMBING
J 0
(-6075 4975);
DISPLAY 0.872340 (-6075 4975);
PAINT GREEN (-6075 4975);
DISPLAY INVISIBLE (-6075 4975);
FORCEPROP 1 LAST HDL_TAP TRUE
J 0
(-5750 4800);
DISPLAY 0.872340 (-5750 4800);
DISPLAY INVISIBLE (-5750 4800);
FORCEPROP 1 LAST PATH I113
J 0
(-6077 4925);
DISPLAY 0.872340 (-6077 4925);
PAINT GREEN (-6077 4925);
DISPLAY INVISIBLE (-6077 4925);
FORCEADD TAP..1
(-6075 4975);
FORCEPROP 3 LASTPIN (-6125 4975) SIG_NAME M_B_CPU1_SA_DQ<20>
J 0
(-6115 4985);
DISPLAY 0.659574 (-6115 4985);
PAINT MONO (-6115 4985);
DISPLAY INVISIBLE (-6115 4985);
FORCEPROP 1 LASTPIN (-6125 4975) BN 20
J 0
(-6137 4983);
DISPLAY 0.489362 (-6137 4983);
PAINT GREEN (-6137 4983);
FORCEPROP 2 LAST CDS_LIB mstr_standard
J 0
(-6075 4975);
DISPLAY 0.723404 (-6075 4975);
PAINT MONO (-6075 4975);
DISPLAY INVISIBLE (-6075 4975);
FORCEPROP 1 LAST BODY_TYPE PLUMBING
J 0
(-6075 5025);
DISPLAY 0.872340 (-6075 5025);
PAINT GREEN (-6075 5025);
DISPLAY INVISIBLE (-6075 5025);
FORCEPROP 1 LAST HDL_TAP TRUE
J 0
(-5750 4850);
DISPLAY 0.872340 (-5750 4850);
DISPLAY INVISIBLE (-5750 4850);
FORCEPROP 1 LAST PATH I114
J 0
(-6077 4975);
DISPLAY 0.872340 (-6077 4975);
PAINT GREEN (-6077 4975);
DISPLAY INVISIBLE (-6077 4975);
FORCEADD TAP..1
(-6075 4875);
FORCEPROP 3 LASTPIN (-6125 4875) SIG_NAME M_B_CPU1_SA_DQ<18>
J 0
(-6115 4885);
DISPLAY 0.659574 (-6115 4885);
PAINT MONO (-6115 4885);
DISPLAY INVISIBLE (-6115 4885);
FORCEPROP 1 LASTPIN (-6125 4875) BN 18
J 0
(-6137 4883);
DISPLAY 0.489362 (-6137 4883);
PAINT GREEN (-6137 4883);
FORCEPROP 2 LAST CDS_LIB mstr_standard
J 0
(-6075 4875);
DISPLAY 0.723404 (-6075 4875);
PAINT MONO (-6075 4875);
DISPLAY INVISIBLE (-6075 4875);
FORCEPROP 1 LAST BODY_TYPE PLUMBING
J 0
(-6075 4925);
DISPLAY 0.872340 (-6075 4925);
PAINT GREEN (-6075 4925);
DISPLAY INVISIBLE (-6075 4925);
FORCEPROP 1 LAST HDL_TAP TRUE
J 0
(-5750 4750);
DISPLAY 0.872340 (-5750 4750);
DISPLAY INVISIBLE (-5750 4750);
FORCEPROP 1 LAST PATH I115
J 0
(-6077 4875);
DISPLAY 0.872340 (-6077 4875);
PAINT GREEN (-6077 4875);
DISPLAY INVISIBLE (-6077 4875);
FORCEADD TAP..1
(-6075 5125);
FORCEPROP 3 LASTPIN (-6125 5125) SIG_NAME M_B_CPU1_SA_DQ<23>
J 0
(-6115 5135);
DISPLAY 0.659574 (-6115 5135);
PAINT MONO (-6115 5135);
DISPLAY INVISIBLE (-6115 5135);
FORCEPROP 1 LASTPIN (-6125 5125) BN 23
J 0
(-6137 5133);
DISPLAY 0.489362 (-6137 5133);
PAINT GREEN (-6137 5133);
FORCEPROP 2 LAST CDS_LIB mstr_standard
J 0
(-6075 5125);
DISPLAY 0.723404 (-6075 5125);
PAINT MONO (-6075 5125);
DISPLAY INVISIBLE (-6075 5125);
FORCEPROP 1 LAST BODY_TYPE PLUMBING
J 0
(-6075 5175);
DISPLAY 0.872340 (-6075 5175);
PAINT GREEN (-6075 5175);
DISPLAY INVISIBLE (-6075 5175);
FORCEPROP 1 LAST HDL_TAP TRUE
J 0
(-5750 5000);
DISPLAY 0.872340 (-5750 5000);
DISPLAY INVISIBLE (-5750 5000);
FORCEPROP 1 LAST PATH I116
J 0
(-6077 5125);
DISPLAY 0.872340 (-6077 5125);
PAINT GREEN (-6077 5125);
DISPLAY INVISIBLE (-6077 5125);
FORCEADD TAP..1
(-6075 5175);
FORCEPROP 3 LASTPIN (-6125 5175) SIG_NAME M_B_CPU1_SA_DQ<24>
J 0
(-6115 5185);
DISPLAY 0.659574 (-6115 5185);
PAINT MONO (-6115 5185);
DISPLAY INVISIBLE (-6115 5185);
FORCEPROP 1 LASTPIN (-6125 5175) BN 24
J 0
(-6137 5183);
DISPLAY 0.489362 (-6137 5183);
PAINT GREEN (-6137 5183);
FORCEPROP 2 LAST CDS_LIB mstr_standard
J 0
(-6075 5175);
DISPLAY 0.723404 (-6075 5175);
PAINT MONO (-6075 5175);
DISPLAY INVISIBLE (-6075 5175);
FORCEPROP 1 LAST BODY_TYPE PLUMBING
J 0
(-6075 5225);
DISPLAY 0.872340 (-6075 5225);
PAINT GREEN (-6075 5225);
DISPLAY INVISIBLE (-6075 5225);
FORCEPROP 1 LAST HDL_TAP TRUE
J 0
(-5750 5050);
DISPLAY 0.872340 (-5750 5050);
DISPLAY INVISIBLE (-5750 5050);
FORCEPROP 1 LAST PATH I117
J 0
(-6077 5175);
DISPLAY 0.872340 (-6077 5175);
PAINT GREEN (-6077 5175);
DISPLAY INVISIBLE (-6077 5175);
FORCEADD TAP..1
(-6075 5225);
FORCEPROP 3 LASTPIN (-6125 5225) SIG_NAME M_B_CPU1_SA_DQ<25>
J 0
(-6115 5235);
DISPLAY 0.659574 (-6115 5235);
PAINT MONO (-6115 5235);
DISPLAY INVISIBLE (-6115 5235);
FORCEPROP 1 LASTPIN (-6125 5225) BN 25
J 0
(-6137 5233);
DISPLAY 0.489362 (-6137 5233);
PAINT GREEN (-6137 5233);
FORCEPROP 2 LAST CDS_LIB mstr_standard
J 0
(-6075 5225);
DISPLAY 0.723404 (-6075 5225);
PAINT MONO (-6075 5225);
DISPLAY INVISIBLE (-6075 5225);
FORCEPROP 1 LAST BODY_TYPE PLUMBING
J 0
(-6075 5275);
DISPLAY 0.872340 (-6075 5275);
PAINT GREEN (-6075 5275);
DISPLAY INVISIBLE (-6075 5275);
FORCEPROP 1 LAST HDL_TAP TRUE
J 0
(-5750 5100);
DISPLAY 0.872340 (-5750 5100);
DISPLAY INVISIBLE (-5750 5100);
FORCEPROP 1 LAST PATH I118
J 0
(-6077 5225);
DISPLAY 0.872340 (-6077 5225);
PAINT GREEN (-6077 5225);
DISPLAY INVISIBLE (-6077 5225);
FORCEADD TAP..1
(-6075 5375);
FORCEPROP 3 LASTPIN (-6125 5375) SIG_NAME M_B_CPU1_SA_DQ<28>
J 0
(-6115 5385);
DISPLAY 0.659574 (-6115 5385);
PAINT MONO (-6115 5385);
DISPLAY INVISIBLE (-6115 5385);
FORCEPROP 1 LASTPIN (-6125 5375) BN 28
J 0
(-6137 5383);
DISPLAY 0.489362 (-6137 5383);
PAINT GREEN (-6137 5383);
FORCEPROP 2 LAST CDS_LIB mstr_standard
J 0
(-6075 5375);
DISPLAY 0.723404 (-6075 5375);
PAINT MONO (-6075 5375);
DISPLAY INVISIBLE (-6075 5375);
FORCEPROP 1 LAST BODY_TYPE PLUMBING
J 0
(-6075 5425);
DISPLAY 0.872340 (-6075 5425);
PAINT GREEN (-6075 5425);
DISPLAY INVISIBLE (-6075 5425);
FORCEPROP 1 LAST HDL_TAP TRUE
J 0
(-5750 5250);
DISPLAY 0.872340 (-5750 5250);
DISPLAY INVISIBLE (-5750 5250);
FORCEPROP 1 LAST PATH I119
J 0
(-6077 5375);
DISPLAY 0.872340 (-6077 5375);
PAINT GREEN (-6077 5375);
DISPLAY INVISIBLE (-6077 5375);
FORCEADD OFFPAGE..1
(-8375 4725);
FORCEPROP 2 LAST $XR0 38 
J 0
(-8626 4725);
DISPLAY 0.638298 (-8626 4725);
PAINT MONO (-8626 4725);
FORCEPROP 2 LAST CDS_LIB mstr_standard
J 0
(-8375 4725);
DISPLAY 0.723404 (-8375 4725);
PAINT MONO (-8375 4725);
DISPLAY INVISIBLE (-8375 4725);
FORCEPROP 1 LAST OFFPAGE TRUE
J 0
(-8050 4600);
DISPLAY 0.872340 (-8050 4600);
PAINT GREEN (-8050 4600);
DISPLAY INVISIBLE (-8050 4600);
FORCEPROP 1 LAST COMMENT_BODY TRUE
J 0
(-8250 4625);
DISPLAY 0.872340 (-8250 4625);
PAINT GREEN (-8250 4625);
DISPLAY INVISIBLE (-8250 4625);
FORCEPROP 2 LAST PATH I12
J 0
(-8575 4775);
DISPLAY 1.021277 (-8575 4775);
DISPLAY INVISIBLE (-8575 4775);
FORCEADD TAP..1
(-6075 5325);
FORCEPROP 3 LASTPIN (-6125 5325) SIG_NAME M_B_CPU1_SA_DQ<27>
J 0
(-6115 5335);
DISPLAY 0.659574 (-6115 5335);
PAINT MONO (-6115 5335);
DISPLAY INVISIBLE (-6115 5335);
FORCEPROP 1 LASTPIN (-6125 5325) BN 27
J 0
(-6137 5333);
DISPLAY 0.489362 (-6137 5333);
PAINT GREEN (-6137 5333);
FORCEPROP 2 LAST CDS_LIB mstr_standard
J 0
(-6075 5325);
DISPLAY 0.723404 (-6075 5325);
PAINT MONO (-6075 5325);
DISPLAY INVISIBLE (-6075 5325);
FORCEPROP 1 LAST BODY_TYPE PLUMBING
J 0
(-6075 5375);
DISPLAY 0.872340 (-6075 5375);
PAINT GREEN (-6075 5375);
DISPLAY INVISIBLE (-6075 5375);
FORCEPROP 1 LAST HDL_TAP TRUE
J 0
(-5750 5200);
DISPLAY 0.872340 (-5750 5200);
DISPLAY INVISIBLE (-5750 5200);
FORCEPROP 1 LAST PATH I120
J 0
(-6077 5325);
DISPLAY 0.872340 (-6077 5325);
PAINT GREEN (-6077 5325);
DISPLAY INVISIBLE (-6077 5325);
FORCEADD TAP..1
(-6075 5275);
FORCEPROP 3 LASTPIN (-6125 5275) SIG_NAME M_B_CPU1_SA_DQ<26>
J 0
(-6115 5285);
DISPLAY 0.659574 (-6115 5285);
PAINT MONO (-6115 5285);
DISPLAY INVISIBLE (-6115 5285);
FORCEPROP 1 LASTPIN (-6125 5275) BN 26
J 0
(-6137 5283);
DISPLAY 0.489362 (-6137 5283);
PAINT GREEN (-6137 5283);
FORCEPROP 2 LAST CDS_LIB mstr_standard
J 0
(-6075 5275);
DISPLAY 0.723404 (-6075 5275);
PAINT MONO (-6075 5275);
DISPLAY INVISIBLE (-6075 5275);
FORCEPROP 1 LAST BODY_TYPE PLUMBING
J 0
(-6075 5325);
DISPLAY 0.872340 (-6075 5325);
PAINT GREEN (-6075 5325);
DISPLAY INVISIBLE (-6075 5325);
FORCEPROP 1 LAST HDL_TAP TRUE
J 0
(-5750 5150);
DISPLAY 0.872340 (-5750 5150);
DISPLAY INVISIBLE (-5750 5150);
FORCEPROP 1 LAST PATH I121
J 0
(-6077 5275);
DISPLAY 0.872340 (-6077 5275);
PAINT GREEN (-6077 5275);
DISPLAY INVISIBLE (-6077 5275);
FORCEADD TAP..1
(-6075 5475);
FORCEPROP 3 LASTPIN (-6125 5475) SIG_NAME M_B_CPU1_SA_DQ<30>
J 0
(-6115 5485);
DISPLAY 0.659574 (-6115 5485);
PAINT MONO (-6115 5485);
DISPLAY INVISIBLE (-6115 5485);
FORCEPROP 1 LASTPIN (-6125 5475) BN 30
J 0
(-6137 5483);
DISPLAY 0.489362 (-6137 5483);
PAINT GREEN (-6137 5483);
FORCEPROP 2 LAST CDS_LIB mstr_standard
J 0
(-6075 5475);
DISPLAY 0.723404 (-6075 5475);
PAINT MONO (-6075 5475);
DISPLAY INVISIBLE (-6075 5475);
FORCEPROP 1 LAST BODY_TYPE PLUMBING
J 0
(-6075 5525);
DISPLAY 0.872340 (-6075 5525);
PAINT GREEN (-6075 5525);
DISPLAY INVISIBLE (-6075 5525);
FORCEPROP 1 LAST HDL_TAP TRUE
J 0
(-5750 5350);
DISPLAY 0.872340 (-5750 5350);
DISPLAY INVISIBLE (-5750 5350);
FORCEPROP 1 LAST PATH I122
J 0
(-6077 5475);
DISPLAY 0.872340 (-6077 5475);
PAINT GREEN (-6077 5475);
DISPLAY INVISIBLE (-6077 5475);
FORCEADD TAP..1
(-6075 5425);
FORCEPROP 3 LASTPIN (-6125 5425) SIG_NAME M_B_CPU1_SA_DQ<29>
J 0
(-6115 5435);
DISPLAY 0.659574 (-6115 5435);
PAINT MONO (-6115 5435);
DISPLAY INVISIBLE (-6115 5435);
FORCEPROP 1 LASTPIN (-6125 5425) BN 29
J 0
(-6137 5433);
DISPLAY 0.489362 (-6137 5433);
PAINT GREEN (-6137 5433);
FORCEPROP 2 LAST CDS_LIB mstr_standard
J 0
(-6075 5425);
DISPLAY 0.723404 (-6075 5425);
PAINT MONO (-6075 5425);
DISPLAY INVISIBLE (-6075 5425);
FORCEPROP 1 LAST BODY_TYPE PLUMBING
J 0
(-6075 5475);
DISPLAY 0.872340 (-6075 5475);
PAINT GREEN (-6075 5475);
DISPLAY INVISIBLE (-6075 5475);
FORCEPROP 1 LAST HDL_TAP TRUE
J 0
(-5750 5300);
DISPLAY 0.872340 (-5750 5300);
DISPLAY INVISIBLE (-5750 5300);
FORCEPROP 1 LAST PATH I123
J 0
(-6077 5425);
DISPLAY 0.872340 (-6077 5425);
PAINT GREEN (-6077 5425);
DISPLAY INVISIBLE (-6077 5425);
FORCEADD TAP..1
(-6075 5525);
FORCEPROP 3 LASTPIN (-6125 5525) SIG_NAME M_B_CPU1_SA_DQ<31>
J 0
(-6115 5535);
DISPLAY 0.659574 (-6115 5535);
PAINT MONO (-6115 5535);
DISPLAY INVISIBLE (-6115 5535);
FORCEPROP 1 LASTPIN (-6125 5525) BN 31
J 0
(-6137 5533);
DISPLAY 0.489362 (-6137 5533);
PAINT GREEN (-6137 5533);
FORCEPROP 2 LAST CDS_LIB mstr_standard
J 0
(-6075 5525);
DISPLAY 0.723404 (-6075 5525);
PAINT MONO (-6075 5525);
DISPLAY INVISIBLE (-6075 5525);
FORCEPROP 1 LAST BODY_TYPE PLUMBING
J 0
(-6075 5575);
DISPLAY 0.872340 (-6075 5575);
PAINT GREEN (-6075 5575);
DISPLAY INVISIBLE (-6075 5575);
FORCEPROP 1 LAST HDL_TAP TRUE
J 0
(-5750 5400);
DISPLAY 0.872340 (-5750 5400);
DISPLAY INVISIBLE (-5750 5400);
FORCEPROP 1 LAST PATH I124
J 0
(-6077 5525);
DISPLAY 0.872340 (-6077 5525);
PAINT GREEN (-6077 5525);
DISPLAY INVISIBLE (-6077 5525);
FORCEADD OFFPAGE..3
(-5325 5575);
FORCEPROP 2 LAST $XR0 38 
J 0
(-5111 5575);
DISPLAY 0.638298 (-5111 5575);
PAINT MONO (-5111 5575);
FORCEPROP 2 LAST CDS_LIB mstr_standard
J 0
(-5325 5575);
DISPLAY 0.723404 (-5325 5575);
PAINT MONO (-5325 5575);
DISPLAY INVISIBLE (-5325 5575);
FORCEPROP 1 LAST OFFPAGE TRUE
J 0
(-5000 5450);
DISPLAY 0.872340 (-5000 5450);
PAINT GREEN (-5000 5450);
DISPLAY INVISIBLE (-5000 5450);
FORCEPROP 1 LAST COMMENT_BODY TRUE
J 0
(-5375 5475);
DISPLAY 0.872340 (-5375 5475);
PAINT GREEN (-5375 5475);
DISPLAY INVISIBLE (-5375 5475);
FORCEPROP 2 LAST PATH I125
J 0
(-5100 5625);
DISPLAY 1.021277 (-5100 5625);
DISPLAY INVISIBLE (-5100 5625);
FORCEADD GND..1
(-6475 1225);
FORCEPROP 3 LASTPIN (-6475 1275) SIG_NAME GND\g
J 0
(-6465 1285);
DISPLAY 0.659574 (-6465 1285);
PAINT MONO (-6465 1285);
DISPLAY INVISIBLE (-6465 1285);
FORCEPROP 2 LAST CDS_LIB mstr_symbols
J 0
(-6475 1225);
DISPLAY 0.808511 (-6475 1225);
DISPLAY INVISIBLE (-6475 1225);
FORCEPROP 1 LAST SIZE 1B
J 0
(-6400 1175);
DISPLAY 0.851064 (-6400 1175);
PAINT GREEN (-6400 1175);
DISPLAY INVISIBLE (-6400 1175);
FORCEPROP 2 LAST BOM_COST MEM
J 0
(-6575 1300);
DISPLAY 0.808511 (-6575 1300);
DISPLAY INVISIBLE (-6575 1300);
FORCEPROP 1 LAST VOLTAGE 0.0
J 0
(-6520 1182);
DISPLAY 0.723404 (-6520 1182);
PAINT SKYBLUE (-6520 1182);
DISPLAY INVISIBLE (-6520 1182);
FORCEPROP 1 LAST BODY_TYPE PLUMBING
J 0
(-6520 1182);
DISPLAY 0.340426 (-6520 1182);
PAINT GREEN (-6520 1182);
DISPLAY INVISIBLE (-6520 1182);
FORCEPROP 1 LAST HDL_POWER GND
J 0
(-6475 1375);
DISPLAY 0.851064 (-6475 1375);
PAINT GREEN (-6475 1375);
DISPLAY INVISIBLE (-6475 1375);
FORCEPROP 1 LAST PATH I126
J 0
(-6400 1225);
DISPLAY 0.872340 (-6400 1225);
PAINT AQUA (-6400 1225);
DISPLAY INVISIBLE (-6400 1225);
FORCEADD Q_RES..2
(-6475 1450);
FORCEPROP 1 LAST LOCATION R770
J 0
(-6430 1575);
DISPLAY 0.489362 (-6430 1575);
PAINT SKYBLUE (-6430 1575);
FORCEPROP 0 LAST $SEC 1
J 0
(-6425 1625);
DISPLAY 0.680851 (-6425 1625);
PAINT MONO (-6425 1625);
DISPLAY INVISIBLE (-6425 1625);
FORCEPROP 0 LAST CDS_SEC 1
J 0
(-6425 1625);
DISPLAY 1.021277 (-6425 1625);
DISPLAY INVISIBLE (-6425 1625);
FORCEPROP 1 LASTPIN (-6475 1550) $PN 1
J 0
(-6470 1512);
DISPLAY 0.489362 (-6470 1512);
PAINT MONO (-6470 1512);
FORCEPROP 1 LASTPIN (-6475 1350) $PN 2
J 0
(-6470 1360);
DISPLAY 0.489362 (-6470 1360);
PAINT MONO (-6470 1360);
FORCEPROP 1 LAST WATTAGE 1/16W
J 0
(-6435 1425);
DISPLAY 0.489362 (-6435 1425);
PAINT SKYBLUE (-6435 1425);
FORCEPROP 1 LAST MATERIAL CHIP
J 0
(-6435 1375);
DISPLAY 0.489362 (-6435 1375);
PAINT SKYBLUE (-6435 1375);
FORCEPROP 1 LAST TOLERANCE 1%
J 0
(-6430 1475);
DISPLAY 0.489362 (-6430 1475);
PAINT SKYBLUE (-6430 1475);
FORCEPROP 1 LAST VALUE 15.4K
J 0
(-6430 1525);
DISPLAY 0.489362 (-6430 1525);
PAINT SKYBLUE (-6430 1525);
FORCEPROP 1 LAST PACK_TYPE 0402LF
J 0
(-6435 1275);
DISPLAY 0.489362 (-6435 1275);
PAINT SKYBLUE (-6435 1275);
FORCEPROP 2 LAST CDS_LIB pure_quanta
J 0
(-6475 1450);
DISPLAY INVISIBLE (-6475 1450);
FORCEPROP 1 LAST PATH I127
J 0
(-6425 1625);
DISPLAY 0.978723 (-6425 1625);
PAINT WHITE (-6425 1625);
DISPLAY INVISIBLE (-6425 1625);
FORCEPROP 1 LAST PART_NUMBER CS31542FB02
J 0
(-6435 1325);
DISPLAY 0.489362 (-6435 1325);
PAINT SKYBLUE (-6435 1325);
DISPLAY INVISIBLE (-6435 1325);
FORCEADD GND..1
(-2175 1725);
FORCEPROP 3 LASTPIN (-2175 1775) SIG_NAME GND\g
J 0
(-2165 1785);
DISPLAY 0.659574 (-2165 1785);
PAINT MONO (-2165 1785);
DISPLAY INVISIBLE (-2165 1785);
FORCEPROP 1 LAST SIZE 1B
J 0
(-2100 1675);
DISPLAY 0.851064 (-2100 1675);
PAINT GREEN (-2100 1675);
DISPLAY INVISIBLE (-2100 1675);
FORCEPROP 2 LAST CDS_LIB mstr_symbols
J 0
(-2175 1725);
DISPLAY 0.723404 (-2175 1725);
DISPLAY INVISIBLE (-2175 1725);
FORCEPROP 1 LAST VOLTAGE 0.0
J 0
(-2220 1682);
DISPLAY 0.723404 (-2220 1682);
PAINT SKYBLUE (-2220 1682);
DISPLAY INVISIBLE (-2220 1682);
FORCEPROP 1 LAST BODY_TYPE PLUMBING
J 0
(-2220 1682);
DISPLAY 0.340426 (-2220 1682);
PAINT GREEN (-2220 1682);
DISPLAY INVISIBLE (-2220 1682);
FORCEPROP 1 LAST HDL_POWER GND
J 0
(-2175 1875);
DISPLAY 0.851064 (-2175 1875);
PAINT GREEN (-2175 1875);
DISPLAY INVISIBLE (-2175 1875);
FORCEPROP 1 LAST PATH I128
J 0
(-2100 1725);
DISPLAY 0.872340 (-2100 1725);
PAINT AQUA (-2100 1725);
DISPLAY INVISIBLE (-2100 1725);
FORCEADD OFFPAGE..5
(-7250 1625);
FORCEPROP 2 LAST $XR0 99 
J 0
(-7504 1625);
DISPLAY 0.638298 (-7504 1625);
PAINT MONO (-7504 1625);
FORCEPROP 2 LAST CDS_LIB mstr_standard
J 0
(-7250 1625);
DISPLAY 0.808511 (-7250 1625);
DISPLAY INVISIBLE (-7250 1625);
FORCEPROP 2 LAST BOM_COST MEM
J 0
(-7325 1700);
DISPLAY 0.808511 (-7325 1700);
DISPLAY INVISIBLE (-7325 1700);
FORCEPROP 1 LAST OFFPAGE TRUE
J 0
(-6925 1500);
DISPLAY 0.872340 (-6925 1500);
PAINT GREEN (-6925 1500);
DISPLAY INVISIBLE (-6925 1500);
FORCEPROP 1 LAST COMMENT_BODY TRUE
J 0
(-7150 1550);
DISPLAY 0.872340 (-7150 1550);
PAINT GREEN (-7150 1550);
DISPLAY INVISIBLE (-7150 1550);
FORCEPROP 2 LAST PATH I129
J 0
(-7500 1675);
DISPLAY 1.021277 (-7500 1675);
DISPLAY INVISIBLE (-7500 1675);
FORCEADD OFFPAGE..1
(-8375 4575);
FORCEPROP 2 LAST $XR0 38 
J 0
(-8626 4575);
DISPLAY 0.638298 (-8626 4575);
PAINT MONO (-8626 4575);
FORCEPROP 2 LAST CDS_LIB mstr_standard
J 0
(-8375 4575);
DISPLAY 0.723404 (-8375 4575);
PAINT MONO (-8375 4575);
DISPLAY INVISIBLE (-8375 4575);
FORCEPROP 1 LAST OFFPAGE TRUE
J 0
(-8050 4450);
DISPLAY 0.872340 (-8050 4450);
PAINT GREEN (-8050 4450);
DISPLAY INVISIBLE (-8050 4450);
FORCEPROP 1 LAST COMMENT_BODY TRUE
J 0
(-8250 4475);
DISPLAY 0.872340 (-8250 4475);
PAINT GREEN (-8250 4475);
DISPLAY INVISIBLE (-8250 4475);
FORCEPROP 2 LAST PATH I13
J 0
(-8575 4625);
DISPLAY 1.021277 (-8575 4625);
DISPLAY INVISIBLE (-8575 4625);
FORCEADD OFFPAGE..1
(-8375 4525);
FORCEPROP 2 LAST $XR0 38 
J 0
(-8626 4525);
DISPLAY 0.638298 (-8626 4525);
PAINT MONO (-8626 4525);
FORCEPROP 2 LAST CDS_LIB mstr_standard
J 0
(-8375 4525);
DISPLAY 0.808511 (-8375 4525);
DISPLAY INVISIBLE (-8375 4525);
FORCEPROP 1 LAST OFFPAGE TRUE
J 0
(-8050 4400);
DISPLAY 0.872340 (-8050 4400);
PAINT GREEN (-8050 4400);
DISPLAY INVISIBLE (-8050 4400);
FORCEPROP 1 LAST COMMENT_BODY TRUE
J 0
(-8250 4425);
DISPLAY 0.872340 (-8250 4425);
PAINT GREEN (-8250 4425);
DISPLAY INVISIBLE (-8250 4425);
FORCEPROP 2 LAST PATH I14
J 0
(-8575 4575);
DISPLAY 1.021277 (-8575 4575);
DISPLAY INVISIBLE (-8575 4575);
FORCEADD OFFPAGE..1
(-8375 4425);
FORCEPROP 2 LAST $XR0 38 
J 0
(-8626 4425);
DISPLAY 0.638298 (-8626 4425);
PAINT MONO (-8626 4425);
FORCEPROP 2 LAST CDS_LIB mstr_standard
J 0
(-8375 4425);
DISPLAY 0.723404 (-8375 4425);
PAINT MONO (-8375 4425);
DISPLAY INVISIBLE (-8375 4425);
FORCEPROP 1 LAST OFFPAGE TRUE
J 0
(-8050 4300);
DISPLAY 0.872340 (-8050 4300);
PAINT GREEN (-8050 4300);
DISPLAY INVISIBLE (-8050 4300);
FORCEPROP 1 LAST COMMENT_BODY TRUE
J 0
(-8250 4325);
DISPLAY 0.872340 (-8250 4325);
PAINT GREEN (-8250 4325);
DISPLAY INVISIBLE (-8250 4325);
FORCEPROP 2 LAST PATH I15
J 0
(-8575 4475);
DISPLAY 1.021277 (-8575 4475);
DISPLAY INVISIBLE (-8575 4475);
FORCEADD OFFPAGE..1
(-8375 4375);
FORCEPROP 2 LAST $XR0 38 
J 0
(-8626 4375);
DISPLAY 0.638298 (-8626 4375);
PAINT MONO (-8626 4375);
FORCEPROP 2 LAST CDS_LIB mstr_standard
J 0
(-8375 4375);
DISPLAY 0.808511 (-8375 4375);
DISPLAY INVISIBLE (-8375 4375);
FORCEPROP 1 LAST OFFPAGE TRUE
J 0
(-8050 4250);
DISPLAY 0.872340 (-8050 4250);
PAINT GREEN (-8050 4250);
DISPLAY INVISIBLE (-8050 4250);
FORCEPROP 1 LAST COMMENT_BODY TRUE
J 0
(-8250 4275);
DISPLAY 0.872340 (-8250 4275);
PAINT GREEN (-8250 4275);
DISPLAY INVISIBLE (-8250 4275);
FORCEPROP 2 LAST PATH I16
J 0
(-8575 4425);
DISPLAY 1.021277 (-8575 4425);
DISPLAY INVISIBLE (-8575 4425);
FORCEADD SCONN288_DDR506112002KQ..3
(-1275 3475);
FORCEPROP 1 LAST LOCATION J26
J 0
(-1725 5450);
DISPLAY 0.468085 (-1725 5450);
PAINT SKYBLUE (-1725 5450);
FORCEPROP 0 LAST $SEC 3
J 0
(-1725 5600);
DISPLAY 0.680851 (-1725 5600);
PAINT MONO (-1725 5600);
DISPLAY INVISIBLE (-1725 5600);
FORCEPROP 2 LAST CDS_SEC 3
J 0
(-1725 5600);
DISPLAY 1.021277 (-1725 5600);
DISPLAY INVISIBLE (-1725 5600);
FORCEPROP 0 LASTPIN (-675 1875) $PN G1
J 0
(-665 1885);
DISPLAY 0.680851 (-665 1885);
PAINT MONO (-665 1885);
FORCEPROP 0 LASTPIN (-675 1825) $PN G2
J 0
(-665 1835);
DISPLAY 0.680851 (-665 1835);
PAINT MONO (-665 1835);
FORCEPROP 0 LASTPIN (-675 1775) $PN G3
J 0
(-665 1785);
DISPLAY 0.680851 (-665 1785);
PAINT MONO (-665 1785);
FORCEPROP 0 LASTPIN (-1875 5025) $PN 1
J 2
(-1885 5035);
DISPLAY 0.680851 (-1885 5035);
PAINT MONO (-1885 5035);
FORCEPROP 0 LASTPIN (-1875 5075) $PN 145
J 2
(-1885 5085);
DISPLAY 0.680851 (-1885 5085);
PAINT MONO (-1885 5085);
FORCEPROP 0 LASTPIN (-1875 5125) $PN 146
J 2
(-1885 5135);
DISPLAY 0.680851 (-1885 5135);
PAINT MONO (-1885 5135);
FORCEPROP 0 LASTPIN (-675 1975) $PN 6
J 0
(-665 1985);
DISPLAY 0.680851 (-665 1985);
PAINT MONO (-665 1985);
FORCEPROP 0 LASTPIN (-675 2025) $PN 8
J 0
(-665 2035);
DISPLAY 0.680851 (-665 2035);
PAINT MONO (-665 2035);
FORCEPROP 0 LASTPIN (-675 2075) $PN 10
J 0
(-665 2085);
DISPLAY 0.680851 (-665 2085);
PAINT MONO (-665 2085);
FORCEPROP 0 LASTPIN (-675 2125) $PN 13
J 0
(-665 2135);
DISPLAY 0.680851 (-665 2135);
PAINT MONO (-665 2135);
FORCEPROP 0 LASTPIN (-675 2175) $PN 15
J 0
(-665 2185);
DISPLAY 0.680851 (-665 2185);
PAINT MONO (-665 2185);
FORCEPROP 0 LASTPIN (-675 2225) $PN 17
J 0
(-665 2235);
DISPLAY 0.680851 (-665 2235);
PAINT MONO (-665 2235);
FORCEPROP 0 LASTPIN (-675 2275) $PN 19
J 0
(-665 2285);
DISPLAY 0.680851 (-665 2285);
PAINT MONO (-665 2285);
FORCEPROP 0 LASTPIN (-675 2325) $PN 21
J 0
(-665 2335);
DISPLAY 0.680851 (-665 2335);
PAINT MONO (-665 2335);
FORCEPROP 0 LASTPIN (-675 2375) $PN 24
J 0
(-665 2385);
DISPLAY 0.680851 (-665 2385);
PAINT MONO (-665 2385);
FORCEPROP 0 LASTPIN (-675 2425) $PN 26
J 0
(-665 2435);
DISPLAY 0.680851 (-665 2435);
PAINT MONO (-665 2435);
FORCEPROP 0 LASTPIN (-675 2475) $PN 28
J 0
(-665 2485);
DISPLAY 0.680851 (-665 2485);
PAINT MONO (-665 2485);
FORCEPROP 0 LASTPIN (-675 2525) $PN 30
J 0
(-665 2535);
DISPLAY 0.680851 (-665 2535);
PAINT MONO (-665 2535);
FORCEPROP 0 LASTPIN (-675 2575) $PN 32
J 0
(-665 2585);
DISPLAY 0.680851 (-665 2585);
PAINT MONO (-665 2585);
FORCEPROP 0 LASTPIN (-675 2625) $PN 35
J 0
(-665 2635);
DISPLAY 0.680851 (-665 2635);
PAINT MONO (-665 2635);
FORCEPROP 0 LASTPIN (-675 2675) $PN 37
J 0
(-665 2685);
DISPLAY 0.680851 (-665 2685);
PAINT MONO (-665 2685);
FORCEPROP 0 LASTPIN (-675 2725) $PN 39
J 0
(-665 2735);
DISPLAY 0.680851 (-665 2735);
PAINT MONO (-665 2735);
FORCEPROP 0 LASTPIN (-675 2775) $PN 41
J 0
(-665 2785);
DISPLAY 0.680851 (-665 2785);
PAINT MONO (-665 2785);
FORCEPROP 0 LASTPIN (-675 2825) $PN 43
J 0
(-665 2835);
DISPLAY 0.680851 (-665 2835);
PAINT MONO (-665 2835);
FORCEPROP 0 LASTPIN (-675 2875) $PN 46
J 0
(-665 2885);
DISPLAY 0.680851 (-665 2885);
PAINT MONO (-665 2885);
FORCEPROP 0 LASTPIN (-675 2925) $PN 48
J 0
(-665 2935);
DISPLAY 0.680851 (-665 2935);
PAINT MONO (-665 2935);
FORCEPROP 0 LASTPIN (-675 2975) $PN 50
J 0
(-665 2985);
DISPLAY 0.680851 (-665 2985);
PAINT MONO (-665 2985);
FORCEPROP 0 LASTPIN (-675 3025) $PN 52
J 0
(-665 3035);
DISPLAY 0.680851 (-665 3035);
PAINT MONO (-665 3035);
FORCEPROP 0 LASTPIN (-675 3075) $PN 54
J 0
(-665 3085);
DISPLAY 0.680851 (-665 3085);
PAINT MONO (-665 3085);
FORCEPROP 0 LASTPIN (-675 3125) $PN 57
J 0
(-665 3135);
DISPLAY 0.680851 (-665 3135);
PAINT MONO (-665 3135);
FORCEPROP 0 LASTPIN (-675 3175) $PN 59
J 0
(-665 3185);
DISPLAY 0.680851 (-665 3185);
PAINT MONO (-665 3185);
FORCEPROP 0 LASTPIN (-675 3225) $PN 61
J 0
(-665 3235);
DISPLAY 0.680851 (-665 3235);
PAINT MONO (-665 3235);
FORCEPROP 0 LASTPIN (-675 3275) $PN 63
J 0
(-665 3285);
DISPLAY 0.680851 (-665 3285);
PAINT MONO (-665 3285);
FORCEPROP 0 LASTPIN (-675 3325) $PN 65
J 0
(-665 3335);
DISPLAY 0.680851 (-665 3335);
PAINT MONO (-665 3335);
FORCEPROP 0 LASTPIN (-675 3375) $PN 67
J 0
(-665 3385);
DISPLAY 0.680851 (-665 3385);
PAINT MONO (-665 3385);
FORCEPROP 0 LASTPIN (-675 3425) $PN 69
J 0
(-665 3435);
DISPLAY 0.680851 (-665 3435);
PAINT MONO (-665 3435);
FORCEPROP 0 LASTPIN (-675 3475) $PN 71
J 0
(-665 3485);
DISPLAY 0.680851 (-665 3485);
PAINT MONO (-665 3485);
FORCEPROP 0 LASTPIN (-675 3525) $PN 73
J 0
(-665 3535);
DISPLAY 0.680851 (-665 3535);
PAINT MONO (-665 3535);
FORCEPROP 0 LASTPIN (-675 3575) $PN 75
J 0
(-665 3585);
DISPLAY 0.680851 (-665 3585);
PAINT MONO (-665 3585);
FORCEPROP 0 LASTPIN (-675 3625) $PN 77
J 0
(-665 3635);
DISPLAY 0.680851 (-665 3635);
PAINT MONO (-665 3635);
FORCEPROP 0 LASTPIN (-675 3675) $PN 79
J 0
(-665 3685);
DISPLAY 0.680851 (-665 3685);
PAINT MONO (-665 3685);
FORCEPROP 0 LASTPIN (-675 3725) $PN 81
J 0
(-665 3735);
DISPLAY 0.680851 (-665 3735);
PAINT MONO (-665 3735);
FORCEPROP 0 LASTPIN (-675 3775) $PN 83
J 0
(-665 3785);
DISPLAY 0.680851 (-665 3785);
PAINT MONO (-665 3785);
FORCEPROP 0 LASTPIN (-675 3825) $PN 85
J 0
(-665 3835);
DISPLAY 0.680851 (-665 3835);
PAINT MONO (-665 3835);
FORCEPROP 0 LASTPIN (-675 3875) $PN 88
J 0
(-665 3885);
DISPLAY 0.680851 (-665 3885);
PAINT MONO (-665 3885);
FORCEPROP 0 LASTPIN (-675 3925) $PN 90
J 0
(-665 3935);
DISPLAY 0.680851 (-665 3935);
PAINT MONO (-665 3935);
FORCEPROP 0 LASTPIN (-675 3975) $PN 92
J 0
(-665 3985);
DISPLAY 0.680851 (-665 3985);
PAINT MONO (-665 3985);
FORCEPROP 0 LASTPIN (-675 4025) $PN 95
J 0
(-665 4035);
DISPLAY 0.680851 (-665 4035);
PAINT MONO (-665 4035);
FORCEPROP 0 LASTPIN (-675 4075) $PN 97
J 0
(-665 4085);
DISPLAY 0.680851 (-665 4085);
PAINT MONO (-665 4085);
FORCEPROP 0 LASTPIN (-675 4125) $PN 99
J 0
(-665 4135);
DISPLAY 0.680851 (-665 4135);
PAINT MONO (-665 4135);
FORCEPROP 0 LASTPIN (-675 4175) $PN 101
J 0
(-665 4185);
DISPLAY 0.680851 (-665 4185);
PAINT MONO (-665 4185);
FORCEPROP 0 LASTPIN (-675 4225) $PN 103
J 0
(-665 4235);
DISPLAY 0.680851 (-665 4235);
PAINT MONO (-665 4235);
FORCEPROP 0 LASTPIN (-675 4275) $PN 106
J 0
(-665 4285);
DISPLAY 0.680851 (-665 4285);
PAINT MONO (-665 4285);
FORCEPROP 0 LASTPIN (-675 4325) $PN 108
J 0
(-665 4335);
DISPLAY 0.680851 (-665 4335);
PAINT MONO (-665 4335);
FORCEPROP 0 LASTPIN (-675 4375) $PN 110
J 0
(-665 4385);
DISPLAY 0.680851 (-665 4385);
PAINT MONO (-665 4385);
FORCEPROP 0 LASTPIN (-675 4425) $PN 112
J 0
(-665 4435);
DISPLAY 0.680851 (-665 4435);
PAINT MONO (-665 4435);
FORCEPROP 0 LASTPIN (-675 4475) $PN 114
J 0
(-665 4485);
DISPLAY 0.680851 (-665 4485);
PAINT MONO (-665 4485);
FORCEPROP 0 LASTPIN (-675 4525) $PN 117
J 0
(-665 4535);
DISPLAY 0.680851 (-665 4535);
PAINT MONO (-665 4535);
FORCEPROP 0 LASTPIN (-675 4575) $PN 119
J 0
(-665 4585);
DISPLAY 0.680851 (-665 4585);
PAINT MONO (-665 4585);
FORCEPROP 0 LASTPIN (-675 4625) $PN 121
J 0
(-665 4635);
DISPLAY 0.680851 (-665 4635);
PAINT MONO (-665 4635);
FORCEPROP 0 LASTPIN (-675 4675) $PN 123
J 0
(-665 4685);
DISPLAY 0.680851 (-665 4685);
PAINT MONO (-665 4685);
FORCEPROP 0 LASTPIN (-675 4725) $PN 125
J 0
(-665 4735);
DISPLAY 0.680851 (-665 4735);
PAINT MONO (-665 4735);
FORCEPROP 0 LASTPIN (-675 4775) $PN 128
J 0
(-665 4785);
DISPLAY 0.680851 (-665 4785);
PAINT MONO (-665 4785);
FORCEPROP 0 LASTPIN (-675 4825) $PN 130
J 0
(-665 4835);
DISPLAY 0.680851 (-665 4835);
PAINT MONO (-665 4835);
FORCEPROP 0 LASTPIN (-675 4875) $PN 132
J 0
(-665 4885);
DISPLAY 0.680851 (-665 4885);
PAINT MONO (-665 4885);
FORCEPROP 0 LASTPIN (-675 4925) $PN 134
J 0
(-665 4935);
DISPLAY 0.680851 (-665 4935);
PAINT MONO (-665 4935);
FORCEPROP 0 LASTPIN (-675 4975) $PN 136
J 0
(-665 4985);
DISPLAY 0.680851 (-665 4985);
PAINT MONO (-665 4985);
FORCEPROP 0 LASTPIN (-675 5025) $PN 139
J 0
(-665 5035);
DISPLAY 0.680851 (-665 5035);
PAINT MONO (-665 5035);
FORCEPROP 0 LASTPIN (-675 5075) $PN 141
J 0
(-665 5085);
DISPLAY 0.680851 (-665 5085);
PAINT MONO (-665 5085);
FORCEPROP 0 LASTPIN (-675 5125) $PN 143
J 0
(-665 5135);
DISPLAY 0.680851 (-665 5135);
PAINT MONO (-665 5135);
FORCEPROP 0 LASTPIN (-1875 1875) $PN 151
J 2
(-1885 1885);
DISPLAY 0.680851 (-1885 1885);
PAINT MONO (-1885 1885);
FORCEPROP 0 LASTPIN (-1875 1925) $PN 153
J 2
(-1885 1935);
DISPLAY 0.680851 (-1885 1935);
PAINT MONO (-1885 1935);
FORCEPROP 0 LASTPIN (-1875 1975) $PN 155
J 2
(-1885 1985);
DISPLAY 0.680851 (-1885 1985);
PAINT MONO (-1885 1985);
FORCEPROP 0 LASTPIN (-1875 2025) $PN 158
J 2
(-1885 2035);
DISPLAY 0.680851 (-1885 2035);
PAINT MONO (-1885 2035);
FORCEPROP 0 LASTPIN (-1875 2075) $PN 160
J 2
(-1885 2085);
DISPLAY 0.680851 (-1885 2085);
PAINT MONO (-1885 2085);
FORCEPROP 0 LASTPIN (-1875 2125) $PN 162
J 2
(-1885 2135);
DISPLAY 0.680851 (-1885 2135);
PAINT MONO (-1885 2135);
FORCEPROP 0 LASTPIN (-1875 2175) $PN 164
J 2
(-1885 2185);
DISPLAY 0.680851 (-1885 2185);
PAINT MONO (-1885 2185);
FORCEPROP 0 LASTPIN (-1875 2225) $PN 166
J 2
(-1885 2235);
DISPLAY 0.680851 (-1885 2235);
PAINT MONO (-1885 2235);
FORCEPROP 0 LASTPIN (-1875 2275) $PN 169
J 2
(-1885 2285);
DISPLAY 0.680851 (-1885 2285);
PAINT MONO (-1885 2285);
FORCEPROP 0 LASTPIN (-1875 2325) $PN 171
J 2
(-1885 2335);
DISPLAY 0.680851 (-1885 2335);
PAINT MONO (-1885 2335);
FORCEPROP 0 LASTPIN (-1875 2375) $PN 173
J 2
(-1885 2385);
DISPLAY 0.680851 (-1885 2385);
PAINT MONO (-1885 2385);
FORCEPROP 0 LASTPIN (-1875 2425) $PN 175
J 2
(-1885 2435);
DISPLAY 0.680851 (-1885 2435);
PAINT MONO (-1885 2435);
FORCEPROP 0 LASTPIN (-1875 2475) $PN 177
J 2
(-1885 2485);
DISPLAY 0.680851 (-1885 2485);
PAINT MONO (-1885 2485);
FORCEPROP 0 LASTPIN (-1875 2525) $PN 180
J 2
(-1885 2535);
DISPLAY 0.680851 (-1885 2535);
PAINT MONO (-1885 2535);
FORCEPROP 0 LASTPIN (-1875 2575) $PN 182
J 2
(-1885 2585);
DISPLAY 0.680851 (-1885 2585);
PAINT MONO (-1885 2585);
FORCEPROP 0 LASTPIN (-1875 2625) $PN 184
J 2
(-1885 2635);
DISPLAY 0.680851 (-1885 2635);
PAINT MONO (-1885 2635);
FORCEPROP 0 LASTPIN (-1875 2675) $PN 186
J 2
(-1885 2685);
DISPLAY 0.680851 (-1885 2685);
PAINT MONO (-1885 2685);
FORCEPROP 0 LASTPIN (-1875 2725) $PN 188
J 2
(-1885 2735);
DISPLAY 0.680851 (-1885 2735);
PAINT MONO (-1885 2735);
FORCEPROP 0 LASTPIN (-1875 2775) $PN 191
J 2
(-1885 2785);
DISPLAY 0.680851 (-1885 2785);
PAINT MONO (-1885 2785);
FORCEPROP 0 LASTPIN (-1875 2825) $PN 193
J 2
(-1885 2835);
DISPLAY 0.680851 (-1885 2835);
PAINT MONO (-1885 2835);
FORCEPROP 0 LASTPIN (-1875 2875) $PN 195
J 2
(-1885 2885);
DISPLAY 0.680851 (-1885 2885);
PAINT MONO (-1885 2885);
FORCEPROP 0 LASTPIN (-1875 2925) $PN 197
J 2
(-1885 2935);
DISPLAY 0.680851 (-1885 2935);
PAINT MONO (-1885 2935);
FORCEPROP 0 LASTPIN (-1875 2975) $PN 199
J 2
(-1885 2985);
DISPLAY 0.680851 (-1885 2985);
PAINT MONO (-1885 2985);
FORCEPROP 0 LASTPIN (-1875 3025) $PN 202
J 2
(-1885 3035);
DISPLAY 0.680851 (-1885 3035);
PAINT MONO (-1885 3035);
FORCEPROP 0 LASTPIN (-1875 3075) $PN 204
J 2
(-1885 3085);
DISPLAY 0.680851 (-1885 3085);
PAINT MONO (-1885 3085);
FORCEPROP 0 LASTPIN (-1875 3125) $PN 206
J 2
(-1885 3135);
DISPLAY 0.680851 (-1885 3135);
PAINT MONO (-1885 3135);
FORCEPROP 0 LASTPIN (-1875 3175) $PN 208
J 2
(-1885 3185);
DISPLAY 0.680851 (-1885 3185);
PAINT MONO (-1885 3185);
FORCEPROP 0 LASTPIN (-1875 3225) $PN 210
J 2
(-1885 3235);
DISPLAY 0.680851 (-1885 3235);
PAINT MONO (-1885 3235);
FORCEPROP 0 LASTPIN (-1875 3275) $PN 212
J 2
(-1885 3285);
DISPLAY 0.680851 (-1885 3285);
PAINT MONO (-1885 3285);
FORCEPROP 0 LASTPIN (-1875 3325) $PN 214
J 2
(-1885 3335);
DISPLAY 0.680851 (-1885 3335);
PAINT MONO (-1885 3335);
FORCEPROP 0 LASTPIN (-1875 3375) $PN 216
J 2
(-1885 3385);
DISPLAY 0.680851 (-1885 3385);
PAINT MONO (-1885 3385);
FORCEPROP 0 LASTPIN (-1875 3425) $PN 219
J 2
(-1885 3435);
DISPLAY 0.680851 (-1885 3435);
PAINT MONO (-1885 3435);
FORCEPROP 0 LASTPIN (-1875 3475) $PN 222
J 2
(-1885 3485);
DISPLAY 0.680851 (-1885 3485);
PAINT MONO (-1885 3485);
FORCEPROP 0 LASTPIN (-1875 3525) $PN 224
J 2
(-1885 3535);
DISPLAY 0.680851 (-1885 3535);
PAINT MONO (-1885 3535);
FORCEPROP 0 LASTPIN (-1875 3575) $PN 226
J 2
(-1885 3585);
DISPLAY 0.680851 (-1885 3585);
PAINT MONO (-1885 3585);
FORCEPROP 0 LASTPIN (-1875 3625) $PN 228
J 2
(-1885 3635);
DISPLAY 0.680851 (-1885 3635);
PAINT MONO (-1885 3635);
FORCEPROP 0 LASTPIN (-1875 3675) $PN 230
J 2
(-1885 3685);
DISPLAY 0.680851 (-1885 3685);
PAINT MONO (-1885 3685);
FORCEPROP 0 LASTPIN (-1875 3725) $PN 233
J 2
(-1885 3735);
DISPLAY 0.680851 (-1885 3735);
PAINT MONO (-1885 3735);
FORCEPROP 0 LASTPIN (-1875 3775) $PN 235
J 2
(-1885 3785);
DISPLAY 0.680851 (-1885 3785);
PAINT MONO (-1885 3785);
FORCEPROP 0 LASTPIN (-1875 3825) $PN 237
J 2
(-1885 3835);
DISPLAY 0.680851 (-1885 3835);
PAINT MONO (-1885 3835);
FORCEPROP 0 LASTPIN (-1875 3875) $PN 240
J 2
(-1885 3885);
DISPLAY 0.680851 (-1885 3885);
PAINT MONO (-1885 3885);
FORCEPROP 0 LASTPIN (-1875 3925) $PN 242
J 2
(-1885 3935);
DISPLAY 0.680851 (-1885 3935);
PAINT MONO (-1885 3935);
FORCEPROP 0 LASTPIN (-1875 3975) $PN 244
J 2
(-1885 3985);
DISPLAY 0.680851 (-1885 3985);
PAINT MONO (-1885 3985);
FORCEPROP 0 LASTPIN (-1875 4025) $PN 246
J 2
(-1885 4035);
DISPLAY 0.680851 (-1885 4035);
PAINT MONO (-1885 4035);
FORCEPROP 0 LASTPIN (-1875 4075) $PN 248
J 2
(-1885 4085);
DISPLAY 0.680851 (-1885 4085);
PAINT MONO (-1885 4085);
FORCEPROP 0 LASTPIN (-1875 4125) $PN 251
J 2
(-1885 4135);
DISPLAY 0.680851 (-1885 4135);
PAINT MONO (-1885 4135);
FORCEPROP 0 LASTPIN (-1875 4175) $PN 253
J 2
(-1885 4185);
DISPLAY 0.680851 (-1885 4185);
PAINT MONO (-1885 4185);
FORCEPROP 0 LASTPIN (-1875 4225) $PN 255
J 2
(-1885 4235);
DISPLAY 0.680851 (-1885 4235);
PAINT MONO (-1885 4235);
FORCEPROP 0 LASTPIN (-1875 4275) $PN 257
J 2
(-1885 4285);
DISPLAY 0.680851 (-1885 4285);
PAINT MONO (-1885 4285);
FORCEPROP 0 LASTPIN (-1875 4325) $PN 259
J 2
(-1885 4335);
DISPLAY 0.680851 (-1885 4335);
PAINT MONO (-1885 4335);
FORCEPROP 0 LASTPIN (-1875 4375) $PN 262
J 2
(-1885 4385);
DISPLAY 0.680851 (-1885 4385);
PAINT MONO (-1885 4385);
FORCEPROP 0 LASTPIN (-1875 4425) $PN 264
J 2
(-1885 4435);
DISPLAY 0.680851 (-1885 4435);
PAINT MONO (-1885 4435);
FORCEPROP 0 LASTPIN (-1875 4475) $PN 266
J 2
(-1885 4485);
DISPLAY 0.680851 (-1885 4485);
PAINT MONO (-1885 4485);
FORCEPROP 0 LASTPIN (-1875 4525) $PN 268
J 2
(-1885 4535);
DISPLAY 0.680851 (-1885 4535);
PAINT MONO (-1885 4535);
FORCEPROP 0 LASTPIN (-1875 4575) $PN 270
J 2
(-1885 4585);
DISPLAY 0.680851 (-1885 4585);
PAINT MONO (-1885 4585);
FORCEPROP 0 LASTPIN (-1875 4625) $PN 273
J 2
(-1885 4635);
DISPLAY 0.680851 (-1885 4635);
PAINT MONO (-1885 4635);
FORCEPROP 0 LASTPIN (-1875 4675) $PN 275
J 2
(-1885 4685);
DISPLAY 0.680851 (-1885 4685);
PAINT MONO (-1885 4685);
FORCEPROP 0 LASTPIN (-1875 4725) $PN 277
J 2
(-1885 4735);
DISPLAY 0.680851 (-1885 4735);
PAINT MONO (-1885 4735);
FORCEPROP 0 LASTPIN (-1875 4775) $PN 279
J 2
(-1885 4785);
DISPLAY 0.680851 (-1885 4785);
PAINT MONO (-1885 4785);
FORCEPROP 0 LASTPIN (-1875 4825) $PN 281
J 2
(-1885 4835);
DISPLAY 0.680851 (-1885 4835);
PAINT MONO (-1885 4835);
FORCEPROP 0 LASTPIN (-1875 4875) $PN 284
J 2
(-1885 4885);
DISPLAY 0.680851 (-1885 4885);
PAINT MONO (-1885 4885);
FORCEPROP 0 LASTPIN (-1875 4925) $PN 286
J 2
(-1885 4935);
DISPLAY 0.680851 (-1885 4935);
PAINT MONO (-1885 4935);
FORCEPROP 0 LASTPIN (-1875 4975) $PN 288
J 2
(-1885 4985);
DISPLAY 0.680851 (-1885 4985);
PAINT MONO (-1885 4985);
FORCEPROP 2 LAST PART_TYPE SMLF
J 0
(-1725 5550);
DISPLAY 1.021277 (-1725 5550);
FORCEPROP 2 LAST VALUE SCONN288_DDR506112002KQ
J 0
(-1725 5500);
DISPLAY 0.489362 (-1725 5500);
PAINT SKYBLUE (-1725 5500);
FORCEPROP 1 LAST MATERIAL IO
J 0
(-1725 5300);
DISPLAY 0.468085 (-1725 5300);
PAINT SKYBLUE (-1725 5300);
FORCEPROP 1 LAST CDS_LMAN_SYM_OUTLINE -450,1800,450,-1750
J 0
(-1275 3475);
DISPLAY 0.468085 (-1275 3475);
PAINT GREEN (-1275 3475);
DISPLAY INVISIBLE (-1275 3475);
FORCEPROP 1 LAST NEEDS_NO_SIZE TRUE
J 0
(-1275 3475);
DISPLAY 0.723404 (-1275 3475);
PAINT GREEN (-1275 3475);
DISPLAY INVISIBLE (-1275 3475);
FORCEPROP 2 LAST CDS_LIB pure_quanta
J 0
(-1275 3475);
DISPLAY INVISIBLE (-1275 3475);
FORCEPROP 1 LAST PATH I160
J 0
(-1275 3475);
DISPLAY 0.723404 (-1275 3475);
PAINT GREEN (-1275 3475);
DISPLAY INVISIBLE (-1275 3475);
FORCEPROP 1 LAST PART_NUMBER DFHST8FS479
J 0
(-1725 5375);
DISPLAY 0.468085 (-1725 5375);
PAINT SKYBLUE (-1725 5375);
DISPLAY INVISIBLE (-1725 5375);
FORCEADD GND..1
(-375 1550);
FORCEPROP 3 LASTPIN (-375 1600) SIG_NAME GND\g
J 0
(-365 1610);
DISPLAY 0.659574 (-365 1610);
PAINT MONO (-365 1610);
DISPLAY INVISIBLE (-365 1610);
FORCEPROP 2 LAST CDS_LIB mstr_symbols
J 0
(-375 1550);
DISPLAY 0.723404 (-375 1550);
DISPLAY INVISIBLE (-375 1550);
FORCEPROP 1 LAST SIZE 1B
J 0
(-300 1500);
DISPLAY 0.851064 (-300 1500);
PAINT GREEN (-300 1500);
DISPLAY INVISIBLE (-300 1500);
FORCEPROP 1 LAST VOLTAGE 0.0
J 0
(-420 1507);
DISPLAY 0.723404 (-420 1507);
PAINT SKYBLUE (-420 1507);
DISPLAY INVISIBLE (-420 1507);
FORCEPROP 1 LAST BODY_TYPE PLUMBING
J 0
(-420 1507);
DISPLAY 0.340426 (-420 1507);
PAINT GREEN (-420 1507);
DISPLAY INVISIBLE (-420 1507);
FORCEPROP 1 LAST HDL_POWER GND
J 0
(-375 1700);
DISPLAY 0.851064 (-375 1700);
PAINT GREEN (-375 1700);
DISPLAY INVISIBLE (-375 1700);
FORCEPROP 1 LAST PATH I161
J 0
(-300 1550);
DISPLAY 0.872340 (-300 1550);
PAINT AQUA (-300 1550);
DISPLAY INVISIBLE (-300 1550);
FORCEADD OFFPAGE..1
(-8375 4275);
FORCEPROP 2 LAST $XR0 38 
J 0
(-8626 4275);
DISPLAY 0.638298 (-8626 4275);
PAINT MONO (-8626 4275);
FORCEPROP 2 LAST CDS_LIB mstr_standard
J 0
(-8375 4275);
DISPLAY 0.723404 (-8375 4275);
PAINT MONO (-8375 4275);
DISPLAY INVISIBLE (-8375 4275);
FORCEPROP 1 LAST OFFPAGE TRUE
J 0
(-8050 4150);
DISPLAY 0.872340 (-8050 4150);
PAINT GREEN (-8050 4150);
DISPLAY INVISIBLE (-8050 4150);
FORCEPROP 1 LAST COMMENT_BODY TRUE
J 0
(-8250 4175);
DISPLAY 0.872340 (-8250 4175);
PAINT GREEN (-8250 4175);
DISPLAY INVISIBLE (-8250 4175);
FORCEPROP 2 LAST PATH I17
J 0
(-8575 4325);
DISPLAY 1.021277 (-8575 4325);
DISPLAY INVISIBLE (-8575 4325);
FORCEADD OFFPAGE..1
(-8375 4225);
FORCEPROP 2 LAST $XR0 38 
J 0
(-8626 4225);
DISPLAY 0.638298 (-8626 4225);
PAINT MONO (-8626 4225);
FORCEPROP 2 LAST CDS_LIB mstr_standard
J 0
(-8375 4225);
DISPLAY 0.808511 (-8375 4225);
DISPLAY INVISIBLE (-8375 4225);
FORCEPROP 1 LAST OFFPAGE TRUE
J 0
(-8050 4100);
DISPLAY 0.872340 (-8050 4100);
PAINT GREEN (-8050 4100);
DISPLAY INVISIBLE (-8050 4100);
FORCEPROP 1 LAST COMMENT_BODY TRUE
J 0
(-8250 4125);
DISPLAY 0.872340 (-8250 4125);
PAINT GREEN (-8250 4125);
DISPLAY INVISIBLE (-8250 4125);
FORCEPROP 2 LAST PATH I18
J 0
(-8575 4275);
DISPLAY 1.021277 (-8575 4275);
DISPLAY INVISIBLE (-8575 4275);
FORCEADD Q_CAP..1
R 2
(-8725 3325);
FORCEPROP 1 LAST LOCATION C140
J 2
(-8775 3425);
DISPLAY 0.489362 (-8775 3425);
PAINT SKYBLUE (-8775 3425);
FORCEPROP 0 LAST $SEC 1
J 0
(-8775 3475);
DISPLAY 0.680851 (-8775 3475);
PAINT MONO (-8775 3475);
DISPLAY INVISIBLE (-8775 3475);
FORCEPROP 0 LAST CDS_SEC 1
J 0
(-8775 3475);
DISPLAY 1.021277 (-8775 3475);
DISPLAY INVISIBLE (-8775 3475);
FORCEPROP 1 LASTPIN (-8725 3425) $PN 1
J 2
(-8735 3405);
DISPLAY 0.489362 (-8735 3405);
PAINT MONO (-8735 3405);
FORCEPROP 1 LASTPIN (-8725 3225) $PN 2
J 2
(-8735 3205);
DISPLAY 0.489362 (-8735 3205);
PAINT MONO (-8735 3205);
FORCEPROP 1 LAST PACK_TYPE 0402
J 2
(-8775 3125);
DISPLAY 0.489362 (-8775 3125);
PAINT SKYBLUE (-8775 3125);
FORCEPROP 1 LAST VALUE 0.1UF
J 2
(-8775 3375);
DISPLAY 0.489362 (-8775 3375);
PAINT SKYBLUE (-8775 3375);
FORCEPROP 1 LAST VOLTAGE 25V
J 2
(-8775 3325);
DISPLAY 0.489362 (-8775 3325);
PAINT SKYBLUE (-8775 3325);
FORCEPROP 1 LAST TOLERANCE 10%
J 2
(-8775 3275);
DISPLAY 0.489362 (-8775 3275);
PAINT SKYBLUE (-8775 3275);
FORCEPROP 1 LAST MATERIAL X7R
J 2
(-8775 3225);
DISPLAY 0.489362 (-8775 3225);
PAINT SKYBLUE (-8775 3225);
FORCEPROP 2 LAST CDS_LIB pure_quanta
J 0
(-8725 3325);
DISPLAY INVISIBLE (-8725 3325);
FORCEPROP 0 LAST BOM_COST MEM
J 2
(-8780 3470);
DISPLAY 0.595745 (-8780 3470);
PAINT MONO (-8780 3470);
DISPLAY INVISIBLE (-8780 3470);
FORCEPROP 2 LAST ROOM 
J 2
(-8780 3470);
DISPLAY 0.595745 (-8780 3470);
PAINT RED (-8780 3470);
DISPLAY INVISIBLE (-8780 3470);
FORCEPROP 1 LAST PATH I185
J 2
(-8775 3475);
DISPLAY 0.978723 (-8775 3475);
PAINT WHITE (-8775 3475);
DISPLAY INVISIBLE (-8775 3475);
FORCEPROP 1 LAST PART_NUMBER CH4104K1B00
J 2
(-8775 3175);
DISPLAY 0.489362 (-8775 3175);
PAINT SKYBLUE (-8775 3175);
DISPLAY INVISIBLE (-8775 3175);
FORCEADD GND..1
(-8725 3100);
FORCEPROP 3 LASTPIN (-8725 3150) SIG_NAME GND\g
J 0
(-8715 3160);
DISPLAY 0.659574 (-8715 3160);
PAINT MONO (-8715 3160);
DISPLAY INVISIBLE (-8715 3160);
FORCEPROP 2 LAST BOM_COST MEM
J 0
(-8700 3225);
DISPLAY 0.659574 (-8700 3225);
DISPLAY INVISIBLE (-8700 3225);
FORCEPROP 1 LAST SIZE 1B
J 0
(-8650 3050);
DISPLAY 0.723404 (-8650 3050);
PAINT GREEN (-8650 3050);
DISPLAY INVISIBLE (-8650 3050);
FORCEPROP 2 LAST CDS_LIB mstr_symbols
J 0
(-8725 3100);
DISPLAY 0.808511 (-8725 3100);
DISPLAY INVISIBLE (-8725 3100);
FORCEPROP 1 LAST VOLTAGE 0
J 0
(-8745 3195);
DISPLAY 0.829787 (-8745 3195);
PAINT SKYBLUE (-8745 3195);
DISPLAY INVISIBLE (-8745 3195);
FORCEPROP 2 LAST ROOM MEM_EFGH_DECOUPLING_CAPS
J 0
(-8700 3175);
DISPLAY 0.659574 (-8700 3175);
PAINT RED (-8700 3175);
DISPLAY INVISIBLE (-8700 3175);
FORCEPROP 1 LAST BODY_TYPE PLUMBING
J 0
(-8770 3057);
DISPLAY 0.276596 (-8770 3057);
PAINT GREEN (-8770 3057);
DISPLAY INVISIBLE (-8770 3057);
FORCEPROP 1 LAST HDL_POWER GND
J 0
(-8725 3250);
DISPLAY 0.723404 (-8725 3250);
PAINT GREEN (-8725 3250);
DISPLAY INVISIBLE (-8725 3250);
FORCEPROP 1 LAST PATH I186
J 0
(-8650 3100);
DISPLAY 0.872340 (-8650 3100);
PAINT AQUA (-8650 3100);
DISPLAY INVISIBLE (-8650 3100);
FORCEADD OFFPAGE..6
(-9125 2275);
FORCEPROP 2 LAST $XR4 103 
J 0
(-9579 2275);
DISPLAY 0.638298 (-9579 2275);
PAINT MONO (-9579 2275);
FORCEPROP 2 LAST $XR3 102 
J 0
(-9579 2275);
DISPLAY 0.638298 (-9579 2275);
PAINT MONO (-9579 2275);
FORCEPROP 2 LAST $XR2 101 
J 0
(-9579 2275);
DISPLAY 0.638298 (-9579 2275);
PAINT MONO (-9579 2275);
FORCEPROP 2 LAST $XR1 100 
J 0
(-9579 2275);
DISPLAY 0.638298 (-9579 2275);
PAINT MONO (-9579 2275);
FORCEPROP 2 LAST $XR0 98 
J 0
(-9579 2275);
DISPLAY 0.638298 (-9579 2275);
PAINT MONO (-9579 2275);
FORCEPROP 2 LAST CDS_LIB mstr_standard
J 0
(-9125 2275);
DISPLAY 0.808511 (-9125 2275);
DISPLAY INVISIBLE (-9125 2275);
FORCEPROP 1 LAST OFFPAGE TRUE
J 0
(-8800 2150);
DISPLAY 0.872340 (-8800 2150);
PAINT GREEN (-8800 2150);
DISPLAY INVISIBLE (-8800 2150);
FORCEPROP 1 LAST COMMENT_BODY TRUE
J 0
(-9025 2200);
DISPLAY 0.872340 (-9025 2200);
PAINT GREEN (-9025 2200);
DISPLAY INVISIBLE (-9025 2200);
FORCEPROP 2 LAST PATH I187
J 0
(-9075 2350);
DISPLAY 1.021277 (-9075 2350);
DISPLAY INVISIBLE (-9075 2350);
FORCEADD Q_RES..1
R 2
(-8625 2275);
FORCEPROP 1 LAST LOCATION R304
J 2
(-8600 2300);
DISPLAY 0.489362 (-8600 2300);
PAINT SKYBLUE (-8600 2300);
FORCEPROP 0 LAST $SEC 1
J 0
(-8600 2350);
DISPLAY 0.680851 (-8600 2350);
PAINT MONO (-8600 2350);
DISPLAY INVISIBLE (-8600 2350);
FORCEPROP 0 LAST CDS_SEC 1
J 0
(-8600 2350);
DISPLAY 1.021277 (-8600 2350);
DISPLAY INVISIBLE (-8600 2350);
FORCEPROP 1 LASTPIN (-8525 2275) $PN 1
J 2
(-8537 2287);
DISPLAY 0.489362 (-8537 2287);
PAINT MONO (-8537 2287);
FORCEPROP 1 LASTPIN (-8725 2275) $PN 2
J 2
(-8687 2287);
DISPLAY 0.489362 (-8687 2287);
PAINT MONO (-8687 2287);
FORCEPROP 1 LAST VALUE 1K
J 0
(-8625 2225);
DISPLAY 0.489362 (-8625 2225);
PAINT SKYBLUE (-8625 2225);
FORCEPROP 1 LAST TOLERANCE 1%
J 2
(-8500 2250);
DISPLAY 0.489362 (-8500 2250);
PAINT SKYBLUE (-8500 2250);
DISPLAY INVISIBLE (-8500 2250);
FORCEPROP 2 LAST BOM_COST MEM
J 0
(-8650 2425);
DISPLAY 0.744681 (-8650 2425);
PAINT WHITE (-8650 2425);
DISPLAY INVISIBLE (-8650 2425);
FORCEPROP 2 LAST CDS_LIB pure_quanta
J 0
(-8625 2275);
DISPLAY INVISIBLE (-8625 2275);
FORCEPROP 1 LAST WATTAGE 1/16W
J 0
(-8550 2200);
DISPLAY 0.489362 (-8550 2200);
PAINT SKYBLUE (-8550 2200);
DISPLAY INVISIBLE (-8550 2200);
FORCEPROP 1 LAST MATERIAL CHIP
J 0
(-8800 2250);
DISPLAY 0.489362 (-8800 2250);
PAINT SKYBLUE (-8800 2250);
DISPLAY INVISIBLE (-8800 2250);
FORCEPROP 1 LAST PACK_TYPE 0402LF
J 0
(-8800 2200);
DISPLAY 0.489362 (-8800 2200);
PAINT SKYBLUE (-8800 2200);
DISPLAY INVISIBLE (-8800 2200);
FORCEPROP 2 LAST ROOM 
J 0
(-8650 2375);
DISPLAY 0.744681 (-8650 2375);
PAINT RED (-8650 2375);
DISPLAY INVISIBLE (-8650 2375);
FORCEPROP 1 LAST PATH I188
J 2
(-8575 2425);
DISPLAY 0.978723 (-8575 2425);
PAINT WHITE (-8575 2425);
DISPLAY INVISIBLE (-8575 2425);
FORCEPROP 1 LAST PART_NUMBER CS21002FB06
J 0
(-8725 2325);
DISPLAY 0.489362 (-8725 2325);
PAINT SKYBLUE (-8725 2325);
DISPLAY INVISIBLE (-8725 2325);
FORCEADD VCC_CORE..1
(-8500 2600);
FORCEPROP 3 LASTPIN (-8500 2550) SIG_NAME P3V3\g
J 0
(-8490 2560);
DISPLAY 0.659574 (-8490 2560);
PAINT MONO (-8490 2560);
DISPLAY INVISIBLE (-8490 2560);
FORCEPROP 1 LAST HDL_POWER P3V3
J 1
(-8500 2650);
DISPLAY 0.489362 (-8500 2650);
PAINT GREEN (-8500 2650);
FORCEPROP 2 LAST CDS_LIB mstr_symbols
J 0
(-8500 2600);
DISPLAY INVISIBLE (-8500 2600);
FORCEPROP 0 LAST VOLTAGE 3.3
J 0
(-8775 2750);
DISPLAY 1.021277 (-8775 2750);
PAINT SKYBLUE (-8775 2750);
DISPLAY INVISIBLE (-8775 2750);
FORCEPROP 2 LAST ROOM PVCCINFAON_CPU0_CTRL
J 0
(-8500 2700);
DISPLAY 0.808511 (-8500 2700);
PAINT RED (-8500 2700);
DISPLAY INVISIBLE (-8500 2700);
FORCEPROP 1 LAST PATH I189
J 0
(-8450 2625);
DISPLAY 0.872340 (-8450 2625);
PAINT AQUA (-8450 2625);
DISPLAY INVISIBLE (-8450 2625);
FORCEADD OFFPAGE..6
(-8375 4175);
FORCEPROP 2 LAST $XR0 38 
J 0
(-8654 4175);
DISPLAY 0.638298 (-8654 4175);
PAINT MONO (-8654 4175);
FORCEPROP 2 LAST CDS_LIB mstr_standard
J 0
(-8375 4175);
DISPLAY 0.723404 (-8375 4175);
PAINT MONO (-8375 4175);
DISPLAY INVISIBLE (-8375 4175);
FORCEPROP 1 LAST OFFPAGE TRUE
J 0
(-8050 4050);
DISPLAY 0.872340 (-8050 4050);
PAINT GREEN (-8050 4050);
DISPLAY INVISIBLE (-8050 4050);
FORCEPROP 1 LAST COMMENT_BODY TRUE
J 0
(-8275 4100);
DISPLAY 0.872340 (-8275 4100);
PAINT GREEN (-8275 4100);
DISPLAY INVISIBLE (-8275 4100);
FORCEPROP 2 LAST PATH I19
J 0
(-8600 4225);
DISPLAY 1.021277 (-8600 4225);
DISPLAY INVISIBLE (-8600 4225);
FORCEADD Q_RES..2
(-8500 2425);
FORCEPROP 1 LAST LOCATION R104
J 0
(-8455 2550);
DISPLAY 0.489362 (-8455 2550);
PAINT SKYBLUE (-8455 2550);
FORCEPROP 0 LAST $SEC 1
J 0
(-8450 2600);
DISPLAY 0.680851 (-8450 2600);
PAINT MONO (-8450 2600);
DISPLAY INVISIBLE (-8450 2600);
FORCEPROP 0 LAST CDS_SEC 1
J 0
(-8450 2600);
DISPLAY 1.021277 (-8450 2600);
DISPLAY INVISIBLE (-8450 2600);
FORCEPROP 1 LASTPIN (-8500 2525) $PN 1
J 0
(-8495 2487);
DISPLAY 0.489362 (-8495 2487);
PAINT MONO (-8495 2487);
FORCEPROP 1 LASTPIN (-8500 2325) $PN 2
J 0
(-8495 2335);
DISPLAY 0.489362 (-8495 2335);
PAINT MONO (-8495 2335);
FORCEPROP 1 LAST TOLERANCE 1%
J 0
(-8450 2475);
DISPLAY 0.489362 (-8450 2475);
PAINT SKYBLUE (-8450 2475);
FORCEPROP 1 LAST MATERIAL EMPTY
J 0
(-8450 2425);
DISPLAY 0.489362 (-8450 2425);
PAINT RED (-8450 2425);
FORCEPROP 1 LAST WATTAGE 1/16W
J 0
(-8450 2450);
DISPLAY 0.489362 (-8450 2450);
PAINT SKYBLUE (-8450 2450);
FORCEPROP 1 LAST VALUE 1K
J 0
(-8455 2500);
DISPLAY 0.489362 (-8455 2500);
PAINT SKYBLUE (-8455 2500);
FORCEPROP 1 LAST PACK_TYPE 0402LF
J 0
(-8450 2375);
DISPLAY 0.489362 (-8450 2375);
PAINT SKYBLUE (-8450 2375);
FORCEPROP 2 LAST CDS_LIB pure_quanta
J 2
(-8500 2425);
DISPLAY INVISIBLE (-8500 2425);
FORCEPROP 2 LAST BOM_COST MEM
J 0
(-8450 2600);
DISPLAY 0.808511 (-8450 2600);
DISPLAY INVISIBLE (-8450 2600);
FORCEPROP 2 LAST ROOM 
J 0
(-8450 2650);
DISPLAY 0.808511 (-8450 2650);
PAINT RED (-8450 2650);
DISPLAY INVISIBLE (-8450 2650);
FORCEPROP 1 LAST PATH I190
J 0
(-8450 2600);
DISPLAY 0.978723 (-8450 2600);
PAINT WHITE (-8450 2600);
DISPLAY INVISIBLE (-8450 2600);
FORCEPROP 1 LAST PART_NUMBER CS21002FB06
J 0
(-8450 2400);
DISPLAY 0.489362 (-8450 2400);
PAINT SKYBLUE (-8450 2400);
DISPLAY INVISIBLE (-8450 2400);
FORCEADD TAP..1
(-3250 3750);
FORCEPROP 3 LASTPIN (-3300 3750) SIG_NAME M_B_CPU1_SA_DQS_DN<2>
J 0
(-3290 3760);
DISPLAY 0.659574 (-3290 3760);
PAINT MONO (-3290 3760);
DISPLAY INVISIBLE (-3290 3760);
FORCEPROP 1 LASTPIN (-3300 3750) BN 2
J 0
(-3312 3758);
DISPLAY 0.489362 (-3312 3758);
PAINT GREEN (-3312 3758);
FORCEPROP 2 LAST CDS_LIB mstr_standard
J 0
(-3250 3750);
DISPLAY 0.723404 (-3250 3750);
PAINT MONO (-3250 3750);
DISPLAY INVISIBLE (-3250 3750);
FORCEPROP 1 LAST BODY_TYPE PLUMBING
J 0
(-3250 3800);
DISPLAY 0.872340 (-3250 3800);
PAINT GREEN (-3250 3800);
DISPLAY INVISIBLE (-3250 3800);
FORCEPROP 1 LAST HDL_TAP TRUE
J 0
(-2925 3625);
DISPLAY 0.872340 (-2925 3625);
DISPLAY INVISIBLE (-2925 3625);
FORCEPROP 1 LAST PATH I191
J 0
(-3252 3750);
DISPLAY 0.872340 (-3252 3750);
PAINT GREEN (-3252 3750);
DISPLAY INVISIBLE (-3252 3750);
FORCEADD OFFPAGE..2
(-2450 4550);
FORCEPROP 2 LAST $XR0 38 
J 0
(-2261 4550);
DISPLAY 0.638298 (-2261 4550);
PAINT MONO (-2261 4550);
FORCEPROP 2 LAST CDS_LIB mstr_standard
J 0
(-2450 4550);
DISPLAY 0.723404 (-2450 4550);
PAINT MONO (-2450 4550);
DISPLAY INVISIBLE (-2450 4550);
FORCEPROP 1 LAST OFFPAGE TRUE
J 0
(-2125 4425);
DISPLAY 0.723404 (-2125 4425);
PAINT GREEN (-2125 4425);
DISPLAY INVISIBLE (-2125 4425);
FORCEPROP 1 LAST COMMENT_BODY TRUE
J 0
(-2495 4455);
DISPLAY 0.872340 (-2495 4455);
PAINT GREEN (-2495 4455);
DISPLAY INVISIBLE (-2495 4455);
FORCEPROP 2 LAST PATH I193
J 0
(-2250 4600);
DISPLAY 0.680851 (-2250 4600);
DISPLAY INVISIBLE (-2250 4600);
FORCEADD OFFPAGE..2
(-2450 4500);
FORCEPROP 2 LAST $XR0 38 
J 0
(-2261 4500);
DISPLAY 0.638298 (-2261 4500);
PAINT MONO (-2261 4500);
FORCEPROP 2 LAST CDS_LIB mstr_standard
J 0
(-2450 4500);
DISPLAY 0.723404 (-2450 4500);
PAINT MONO (-2450 4500);
DISPLAY INVISIBLE (-2450 4500);
FORCEPROP 1 LAST OFFPAGE TRUE
J 0
(-2125 4375);
DISPLAY 0.723404 (-2125 4375);
PAINT GREEN (-2125 4375);
DISPLAY INVISIBLE (-2125 4375);
FORCEPROP 1 LAST COMMENT_BODY TRUE
J 0
(-2495 4405);
DISPLAY 0.872340 (-2495 4405);
PAINT GREEN (-2495 4405);
DISPLAY INVISIBLE (-2495 4405);
FORCEPROP 2 LAST PATH I194
J 0
(-2250 4550);
DISPLAY 0.680851 (-2250 4550);
DISPLAY INVISIBLE (-2250 4550);
FORCEADD TAP..1
(-3250 4450);
FORCEPROP 3 LASTPIN (-3300 4450) SIG_NAME M_B_CPU1_SA_DQS_DN<9>
J 0
(-3290 4460);
DISPLAY 0.659574 (-3290 4460);
PAINT MONO (-3290 4460);
DISPLAY INVISIBLE (-3290 4460);
FORCEPROP 1 LASTPIN (-3300 4450) BN 9
J 0
(-3312 4458);
DISPLAY 0.489362 (-3312 4458);
PAINT GREEN (-3312 4458);
FORCEPROP 2 LAST CDS_LIB mstr_standard
J 0
(-3250 4450);
DISPLAY 0.723404 (-3250 4450);
PAINT MONO (-3250 4450);
DISPLAY INVISIBLE (-3250 4450);
FORCEPROP 1 LAST BODY_TYPE PLUMBING
J 0
(-3250 4500);
DISPLAY 0.872340 (-3250 4500);
PAINT GREEN (-3250 4500);
DISPLAY INVISIBLE (-3250 4500);
FORCEPROP 1 LAST HDL_TAP TRUE
J 0
(-2925 4325);
DISPLAY 0.872340 (-2925 4325);
DISPLAY INVISIBLE (-2925 4325);
FORCEPROP 1 LAST PATH I195
J 0
(-3252 4450);
DISPLAY 0.872340 (-3252 4450);
PAINT GREEN (-3252 4450);
DISPLAY INVISIBLE (-3252 4450);
FORCEADD TAP..1
(-3250 4350);
FORCEPROP 3 LASTPIN (-3300 4350) SIG_NAME M_B_CPU1_SA_DQS_DN<8>
J 0
(-3290 4360);
DISPLAY 0.659574 (-3290 4360);
PAINT MONO (-3290 4360);
DISPLAY INVISIBLE (-3290 4360);
FORCEPROP 1 LASTPIN (-3300 4350) BN 8
J 0
(-3312 4358);
DISPLAY 0.489362 (-3312 4358);
PAINT GREEN (-3312 4358);
FORCEPROP 2 LAST CDS_LIB mstr_standard
J 0
(-3250 4350);
DISPLAY 0.723404 (-3250 4350);
PAINT MONO (-3250 4350);
DISPLAY INVISIBLE (-3250 4350);
FORCEPROP 1 LAST BODY_TYPE PLUMBING
J 0
(-3250 4400);
DISPLAY 0.872340 (-3250 4400);
PAINT GREEN (-3250 4400);
DISPLAY INVISIBLE (-3250 4400);
FORCEPROP 1 LAST HDL_TAP TRUE
J 0
(-2925 4225);
DISPLAY 0.872340 (-2925 4225);
DISPLAY INVISIBLE (-2925 4225);
FORCEPROP 1 LAST PATH I196
J 0
(-3252 4350);
DISPLAY 0.872340 (-3252 4350);
PAINT GREEN (-3252 4350);
DISPLAY INVISIBLE (-3252 4350);
FORCEADD TAP..1
(-3250 4250);
FORCEPROP 3 LASTPIN (-3300 4250) SIG_NAME M_B_CPU1_SA_DQS_DN<7>
J 0
(-3290 4260);
DISPLAY 0.659574 (-3290 4260);
PAINT MONO (-3290 4260);
DISPLAY INVISIBLE (-3290 4260);
FORCEPROP 1 LASTPIN (-3300 4250) BN 7
J 0
(-3312 4258);
DISPLAY 0.489362 (-3312 4258);
PAINT GREEN (-3312 4258);
FORCEPROP 2 LAST CDS_LIB mstr_standard
J 0
(-3250 4250);
DISPLAY 0.723404 (-3250 4250);
PAINT MONO (-3250 4250);
DISPLAY INVISIBLE (-3250 4250);
FORCEPROP 1 LAST BODY_TYPE PLUMBING
J 0
(-3250 4300);
DISPLAY 0.872340 (-3250 4300);
PAINT GREEN (-3250 4300);
DISPLAY INVISIBLE (-3250 4300);
FORCEPROP 1 LAST HDL_TAP TRUE
J 0
(-2925 4125);
DISPLAY 0.872340 (-2925 4125);
DISPLAY INVISIBLE (-2925 4125);
FORCEPROP 1 LAST PATH I197
J 0
(-3252 4250);
DISPLAY 0.872340 (-3252 4250);
PAINT GREEN (-3252 4250);
DISPLAY INVISIBLE (-3252 4250);
FORCEADD TAP..1
(-3250 4150);
FORCEPROP 3 LASTPIN (-3300 4150) SIG_NAME M_B_CPU1_SA_DQS_DN<6>
J 0
(-3290 4160);
DISPLAY 0.659574 (-3290 4160);
PAINT MONO (-3290 4160);
DISPLAY INVISIBLE (-3290 4160);
FORCEPROP 1 LASTPIN (-3300 4150) BN 6
J 0
(-3312 4158);
DISPLAY 0.489362 (-3312 4158);
PAINT GREEN (-3312 4158);
FORCEPROP 2 LAST CDS_LIB mstr_standard
J 0
(-3250 4150);
DISPLAY 0.723404 (-3250 4150);
PAINT MONO (-3250 4150);
DISPLAY INVISIBLE (-3250 4150);
FORCEPROP 1 LAST BODY_TYPE PLUMBING
J 0
(-3250 4200);
DISPLAY 0.872340 (-3250 4200);
PAINT GREEN (-3250 4200);
DISPLAY INVISIBLE (-3250 4200);
FORCEPROP 1 LAST HDL_TAP TRUE
J 0
(-2925 4025);
DISPLAY 0.872340 (-2925 4025);
DISPLAY INVISIBLE (-2925 4025);
FORCEPROP 1 LAST PATH I198
J 0
(-3252 4150);
DISPLAY 0.872340 (-3252 4150);
PAINT GREEN (-3252 4150);
DISPLAY INVISIBLE (-3252 4150);
FORCEADD TAP..1
(-3250 4050);
FORCEPROP 3 LASTPIN (-3300 4050) SIG_NAME M_B_CPU1_SA_DQS_DN<5>
J 0
(-3290 4060);
DISPLAY 0.659574 (-3290 4060);
PAINT MONO (-3290 4060);
DISPLAY INVISIBLE (-3290 4060);
FORCEPROP 1 LASTPIN (-3300 4050) BN 5
J 0
(-3312 4058);
DISPLAY 0.489362 (-3312 4058);
PAINT GREEN (-3312 4058);
FORCEPROP 2 LAST CDS_LIB mstr_standard
J 0
(-3250 4050);
DISPLAY 0.723404 (-3250 4050);
PAINT MONO (-3250 4050);
DISPLAY INVISIBLE (-3250 4050);
FORCEPROP 1 LAST BODY_TYPE PLUMBING
J 0
(-3250 4100);
DISPLAY 0.872340 (-3250 4100);
PAINT GREEN (-3250 4100);
DISPLAY INVISIBLE (-3250 4100);
FORCEPROP 1 LAST HDL_TAP TRUE
J 0
(-2925 3925);
DISPLAY 0.872340 (-2925 3925);
DISPLAY INVISIBLE (-2925 3925);
FORCEPROP 1 LAST PATH I199
J 0
(-3252 4050);
DISPLAY 0.872340 (-3252 4050);
PAINT GREEN (-3252 4050);
DISPLAY INVISIBLE (-3252 4050);
FORCEADD OFFPAGE..1
(-8575 3025);
FORCEPROP 2 LAST $XR0 99 
J 0
(-8826 3025);
DISPLAY 0.638298 (-8826 3025);
PAINT MONO (-8826 3025);
FORCEPROP 2 LAST CDS_LIB mstr_standard
J 0
(-8575 3025);
DISPLAY 0.808511 (-8575 3025);
DISPLAY INVISIBLE (-8575 3025);
FORCEPROP 1 LAST OFFPAGE TRUE
J 0
(-8250 2900);
DISPLAY 0.872340 (-8250 2900);
PAINT GREEN (-8250 2900);
DISPLAY INVISIBLE (-8250 2900);
FORCEPROP 1 LAST COMMENT_BODY TRUE
J 0
(-8450 2925);
DISPLAY 0.872340 (-8450 2925);
PAINT GREEN (-8450 2925);
DISPLAY INVISIBLE (-8450 2925);
FORCEPROP 2 LAST PATH I2
J 0
(-8825 3075);
DISPLAY 1.021277 (-8825 3075);
DISPLAY INVISIBLE (-8825 3075);
FORCEADD OFFPAGE..1
(-8375 5575);
FORCEPROP 2 LAST $XR0 38 
J 0
(-8626 5575);
DISPLAY 0.638298 (-8626 5575);
PAINT MONO (-8626 5575);
FORCEPROP 2 LAST CDS_LIB mstr_standard
J 0
(-8375 5575);
DISPLAY 0.723404 (-8375 5575);
PAINT MONO (-8375 5575);
DISPLAY INVISIBLE (-8375 5575);
FORCEPROP 1 LAST OFFPAGE TRUE
J 0
(-8050 5450);
DISPLAY 0.872340 (-8050 5450);
PAINT GREEN (-8050 5450);
DISPLAY INVISIBLE (-8050 5450);
FORCEPROP 1 LAST COMMENT_BODY TRUE
J 0
(-8250 5475);
DISPLAY 0.872340 (-8250 5475);
PAINT GREEN (-8250 5475);
DISPLAY INVISIBLE (-8250 5475);
FORCEPROP 2 LAST PATH I20
J 0
(-8575 5625);
DISPLAY 1.021277 (-8575 5625);
DISPLAY INVISIBLE (-8575 5625);
FORCEADD TAP..1
(-3450 4400);
FORCEPROP 3 LASTPIN (-3500 4400) SIG_NAME M_B_CPU1_SA_DQS_DP<8>
J 0
(-3490 4410);
DISPLAY 0.659574 (-3490 4410);
PAINT MONO (-3490 4410);
DISPLAY INVISIBLE (-3490 4410);
FORCEPROP 1 LASTPIN (-3500 4400) BN 8
J 0
(-3512 4408);
DISPLAY 0.489362 (-3512 4408);
PAINT GREEN (-3512 4408);
FORCEPROP 2 LAST CDS_LIB mstr_standard
J 0
(-3450 4400);
DISPLAY 0.723404 (-3450 4400);
PAINT MONO (-3450 4400);
DISPLAY INVISIBLE (-3450 4400);
FORCEPROP 1 LAST BODY_TYPE PLUMBING
J 0
(-3450 4450);
DISPLAY 0.872340 (-3450 4450);
PAINT GREEN (-3450 4450);
DISPLAY INVISIBLE (-3450 4450);
FORCEPROP 1 LAST HDL_TAP TRUE
J 0
(-3125 4275);
DISPLAY 0.872340 (-3125 4275);
DISPLAY INVISIBLE (-3125 4275);
FORCEPROP 1 LAST PATH I200
J 0
(-3452 4400);
DISPLAY 0.872340 (-3452 4400);
PAINT GREEN (-3452 4400);
DISPLAY INVISIBLE (-3452 4400);
FORCEADD TAP..1
(-3450 4500);
FORCEPROP 3 LASTPIN (-3500 4500) SIG_NAME M_B_CPU1_SA_DQS_DP<9>
J 0
(-3490 4510);
DISPLAY 0.659574 (-3490 4510);
PAINT MONO (-3490 4510);
DISPLAY INVISIBLE (-3490 4510);
FORCEPROP 1 LASTPIN (-3500 4500) BN 9
J 0
(-3512 4508);
DISPLAY 0.489362 (-3512 4508);
PAINT GREEN (-3512 4508);
FORCEPROP 2 LAST CDS_LIB mstr_standard
J 0
(-3450 4500);
DISPLAY 0.723404 (-3450 4500);
PAINT MONO (-3450 4500);
DISPLAY INVISIBLE (-3450 4500);
FORCEPROP 1 LAST BODY_TYPE PLUMBING
J 0
(-3450 4550);
DISPLAY 0.872340 (-3450 4550);
PAINT GREEN (-3450 4550);
DISPLAY INVISIBLE (-3450 4550);
FORCEPROP 1 LAST HDL_TAP TRUE
J 0
(-3125 4375);
DISPLAY 0.872340 (-3125 4375);
DISPLAY INVISIBLE (-3125 4375);
FORCEPROP 1 LAST PATH I201
J 0
(-3452 4500);
DISPLAY 0.872340 (-3452 4500);
PAINT GREEN (-3452 4500);
DISPLAY INVISIBLE (-3452 4500);
FORCEADD TAP..1
(-3450 4300);
FORCEPROP 3 LASTPIN (-3500 4300) SIG_NAME M_B_CPU1_SA_DQS_DP<7>
J 0
(-3490 4310);
DISPLAY 0.659574 (-3490 4310);
PAINT MONO (-3490 4310);
DISPLAY INVISIBLE (-3490 4310);
FORCEPROP 1 LASTPIN (-3500 4300) BN 7
J 0
(-3512 4308);
DISPLAY 0.489362 (-3512 4308);
PAINT GREEN (-3512 4308);
FORCEPROP 2 LAST CDS_LIB mstr_standard
J 0
(-3450 4300);
DISPLAY 0.723404 (-3450 4300);
PAINT MONO (-3450 4300);
DISPLAY INVISIBLE (-3450 4300);
FORCEPROP 1 LAST BODY_TYPE PLUMBING
J 0
(-3450 4350);
DISPLAY 0.872340 (-3450 4350);
PAINT GREEN (-3450 4350);
DISPLAY INVISIBLE (-3450 4350);
FORCEPROP 1 LAST HDL_TAP TRUE
J 0
(-3125 4175);
DISPLAY 0.872340 (-3125 4175);
DISPLAY INVISIBLE (-3125 4175);
FORCEPROP 1 LAST PATH I202
J 0
(-3452 4300);
DISPLAY 0.872340 (-3452 4300);
PAINT GREEN (-3452 4300);
DISPLAY INVISIBLE (-3452 4300);
FORCEADD TAP..1
(-3450 4100);
FORCEPROP 3 LASTPIN (-3500 4100) SIG_NAME M_B_CPU1_SA_DQS_DP<5>
J 0
(-3490 4110);
DISPLAY 0.659574 (-3490 4110);
PAINT MONO (-3490 4110);
DISPLAY INVISIBLE (-3490 4110);
FORCEPROP 1 LASTPIN (-3500 4100) BN 5
J 0
(-3512 4108);
DISPLAY 0.489362 (-3512 4108);
PAINT GREEN (-3512 4108);
FORCEPROP 2 LAST CDS_LIB mstr_standard
J 0
(-3450 4100);
DISPLAY 0.723404 (-3450 4100);
PAINT MONO (-3450 4100);
DISPLAY INVISIBLE (-3450 4100);
FORCEPROP 1 LAST BODY_TYPE PLUMBING
J 0
(-3450 4150);
DISPLAY 0.872340 (-3450 4150);
PAINT GREEN (-3450 4150);
DISPLAY INVISIBLE (-3450 4150);
FORCEPROP 1 LAST HDL_TAP TRUE
J 0
(-3125 3975);
DISPLAY 0.872340 (-3125 3975);
DISPLAY INVISIBLE (-3125 3975);
FORCEPROP 1 LAST PATH I203
J 0
(-3452 4100);
DISPLAY 0.872340 (-3452 4100);
PAINT GREEN (-3452 4100);
DISPLAY INVISIBLE (-3452 4100);
FORCEADD TAP..1
(-3450 4200);
FORCEPROP 3 LASTPIN (-3500 4200) SIG_NAME M_B_CPU1_SA_DQS_DP<6>
J 0
(-3490 4210);
DISPLAY 0.659574 (-3490 4210);
PAINT MONO (-3490 4210);
DISPLAY INVISIBLE (-3490 4210);
FORCEPROP 1 LASTPIN (-3500 4200) BN 6
J 0
(-3512 4208);
DISPLAY 0.489362 (-3512 4208);
PAINT GREEN (-3512 4208);
FORCEPROP 2 LAST CDS_LIB mstr_standard
J 0
(-3450 4200);
DISPLAY 0.723404 (-3450 4200);
PAINT MONO (-3450 4200);
DISPLAY INVISIBLE (-3450 4200);
FORCEPROP 1 LAST BODY_TYPE PLUMBING
J 0
(-3450 4250);
DISPLAY 0.872340 (-3450 4250);
PAINT GREEN (-3450 4250);
DISPLAY INVISIBLE (-3450 4250);
FORCEPROP 1 LAST HDL_TAP TRUE
J 0
(-3125 4075);
DISPLAY 0.872340 (-3125 4075);
DISPLAY INVISIBLE (-3125 4075);
FORCEPROP 1 LAST PATH I204
J 0
(-3452 4200);
DISPLAY 0.872340 (-3452 4200);
PAINT GREEN (-3452 4200);
DISPLAY INVISIBLE (-3452 4200);
FORCEADD OFFPAGE..2
(-2450 3500);
FORCEPROP 2 LAST $XR0 38 
J 0
(-2261 3500);
DISPLAY 0.638298 (-2261 3500);
PAINT MONO (-2261 3500);
FORCEPROP 2 LAST CDS_LIB mstr_standard
J 0
(-2450 3500);
DISPLAY 0.723404 (-2450 3500);
PAINT MONO (-2450 3500);
DISPLAY INVISIBLE (-2450 3500);
FORCEPROP 1 LAST OFFPAGE TRUE
J 0
(-2125 3375);
DISPLAY 0.723404 (-2125 3375);
PAINT GREEN (-2125 3375);
DISPLAY INVISIBLE (-2125 3375);
FORCEPROP 1 LAST COMMENT_BODY TRUE
J 0
(-2495 3405);
DISPLAY 0.872340 (-2495 3405);
PAINT GREEN (-2495 3405);
DISPLAY INVISIBLE (-2495 3405);
FORCEPROP 2 LAST PATH I205
J 0
(-2250 3550);
DISPLAY 0.680851 (-2250 3550);
DISPLAY INVISIBLE (-2250 3550);
FORCEADD OFFPAGE..2
(-2450 3450);
FORCEPROP 2 LAST $XR0 38 
J 0
(-2261 3450);
DISPLAY 0.638298 (-2261 3450);
PAINT MONO (-2261 3450);
FORCEPROP 2 LAST CDS_LIB mstr_standard
J 0
(-2450 3450);
DISPLAY 0.723404 (-2450 3450);
PAINT MONO (-2450 3450);
DISPLAY INVISIBLE (-2450 3450);
FORCEPROP 1 LAST OFFPAGE TRUE
J 0
(-2125 3325);
DISPLAY 0.723404 (-2125 3325);
PAINT GREEN (-2125 3325);
DISPLAY INVISIBLE (-2125 3325);
FORCEPROP 1 LAST COMMENT_BODY TRUE
J 0
(-2495 3355);
DISPLAY 0.872340 (-2495 3355);
PAINT GREEN (-2495 3355);
DISPLAY INVISIBLE (-2495 3355);
FORCEPROP 2 LAST PATH I206
J 0
(-2250 3500);
DISPLAY 0.680851 (-2250 3500);
DISPLAY INVISIBLE (-2250 3500);
FORCEADD TAP..1
(-3250 3950);
FORCEPROP 3 LASTPIN (-3300 3950) SIG_NAME M_B_CPU1_SA_DQS_DN<4>
J 0
(-3290 3960);
DISPLAY 0.659574 (-3290 3960);
PAINT MONO (-3290 3960);
DISPLAY INVISIBLE (-3290 3960);
FORCEPROP 1 LASTPIN (-3300 3950) BN 4
J 0
(-3312 3958);
DISPLAY 0.489362 (-3312 3958);
PAINT GREEN (-3312 3958);
FORCEPROP 2 LAST CDS_LIB mstr_standard
J 0
(-3250 3950);
DISPLAY 0.723404 (-3250 3950);
PAINT MONO (-3250 3950);
DISPLAY INVISIBLE (-3250 3950);
FORCEPROP 1 LAST BODY_TYPE PLUMBING
J 0
(-3250 4000);
DISPLAY 0.872340 (-3250 4000);
PAINT GREEN (-3250 4000);
DISPLAY INVISIBLE (-3250 4000);
FORCEPROP 1 LAST HDL_TAP TRUE
J 0
(-2925 3825);
DISPLAY 0.872340 (-2925 3825);
DISPLAY INVISIBLE (-2925 3825);
FORCEPROP 1 LAST PATH I207
J 0
(-3252 3950);
DISPLAY 0.872340 (-3252 3950);
PAINT GREEN (-3252 3950);
DISPLAY INVISIBLE (-3252 3950);
FORCEADD TAP..1
(-3250 3850);
FORCEPROP 3 LASTPIN (-3300 3850) SIG_NAME M_B_CPU1_SA_DQS_DN<3>
J 0
(-3290 3860);
DISPLAY 0.659574 (-3290 3860);
PAINT MONO (-3290 3860);
DISPLAY INVISIBLE (-3290 3860);
FORCEPROP 1 LASTPIN (-3300 3850) BN 3
J 0
(-3312 3858);
DISPLAY 0.489362 (-3312 3858);
PAINT GREEN (-3312 3858);
FORCEPROP 2 LAST CDS_LIB mstr_standard
J 0
(-3250 3850);
DISPLAY 0.723404 (-3250 3850);
PAINT MONO (-3250 3850);
DISPLAY INVISIBLE (-3250 3850);
FORCEPROP 1 LAST BODY_TYPE PLUMBING
J 0
(-3250 3900);
DISPLAY 0.872340 (-3250 3900);
PAINT GREEN (-3250 3900);
DISPLAY INVISIBLE (-3250 3900);
FORCEPROP 1 LAST HDL_TAP TRUE
J 0
(-2925 3725);
DISPLAY 0.872340 (-2925 3725);
DISPLAY INVISIBLE (-2925 3725);
FORCEPROP 1 LAST PATH I208
J 0
(-3252 3850);
DISPLAY 0.872340 (-3252 3850);
PAINT GREEN (-3252 3850);
DISPLAY INVISIBLE (-3252 3850);
FORCEADD TAP..1
(-3250 3550);
FORCEPROP 3 LASTPIN (-3300 3550) SIG_NAME M_B_CPU1_SA_DQS_DN<0>
J 0
(-3290 3560);
DISPLAY 0.659574 (-3290 3560);
PAINT MONO (-3290 3560);
DISPLAY INVISIBLE (-3290 3560);
FORCEPROP 1 LASTPIN (-3300 3550) BN 0
J 0
(-3312 3558);
DISPLAY 0.489362 (-3312 3558);
PAINT GREEN (-3312 3558);
FORCEPROP 2 LAST CDS_LIB mstr_standard
J 0
(-3250 3550);
DISPLAY 0.723404 (-3250 3550);
PAINT MONO (-3250 3550);
DISPLAY INVISIBLE (-3250 3550);
FORCEPROP 1 LAST BODY_TYPE PLUMBING
J 0
(-3250 3600);
DISPLAY 0.872340 (-3250 3600);
PAINT GREEN (-3250 3600);
DISPLAY INVISIBLE (-3250 3600);
FORCEPROP 1 LAST HDL_TAP TRUE
J 0
(-2925 3425);
DISPLAY 0.872340 (-2925 3425);
DISPLAY INVISIBLE (-2925 3425);
FORCEPROP 1 LAST PATH I209
J 0
(-3252 3550);
DISPLAY 0.872340 (-3252 3550);
PAINT GREEN (-3252 3550);
DISPLAY INVISIBLE (-3252 3550);
FORCEADD OFFPAGE..1
(-8375 5175);
FORCEPROP 2 LAST $XR0 38 
J 0
(-8626 5175);
DISPLAY 0.638298 (-8626 5175);
PAINT MONO (-8626 5175);
FORCEPROP 2 LAST CDS_LIB mstr_standard
J 0
(-8375 5175);
DISPLAY 0.723404 (-8375 5175);
PAINT MONO (-8375 5175);
DISPLAY INVISIBLE (-8375 5175);
FORCEPROP 1 LAST OFFPAGE TRUE
J 0
(-8050 5050);
DISPLAY 0.872340 (-8050 5050);
PAINT GREEN (-8050 5050);
DISPLAY INVISIBLE (-8050 5050);
FORCEPROP 1 LAST COMMENT_BODY TRUE
J 0
(-8250 5075);
DISPLAY 0.872340 (-8250 5075);
PAINT GREEN (-8250 5075);
DISPLAY INVISIBLE (-8250 5075);
FORCEPROP 2 LAST PATH I21
J 0
(-8575 5225);
DISPLAY 1.021277 (-8575 5225);
DISPLAY INVISIBLE (-8575 5225);
FORCEADD TAP..1
(-3250 3650);
FORCEPROP 3 LASTPIN (-3300 3650) SIG_NAME M_B_CPU1_SA_DQS_DN<1>
J 0
(-3290 3660);
DISPLAY 0.659574 (-3290 3660);
PAINT MONO (-3290 3660);
DISPLAY INVISIBLE (-3290 3660);
FORCEPROP 1 LASTPIN (-3300 3650) BN 1
J 0
(-3312 3658);
DISPLAY 0.489362 (-3312 3658);
PAINT GREEN (-3312 3658);
FORCEPROP 2 LAST CDS_LIB mstr_standard
J 0
(-3250 3650);
DISPLAY 0.723404 (-3250 3650);
PAINT MONO (-3250 3650);
DISPLAY INVISIBLE (-3250 3650);
FORCEPROP 1 LAST BODY_TYPE PLUMBING
J 0
(-3250 3700);
DISPLAY 0.872340 (-3250 3700);
PAINT GREEN (-3250 3700);
DISPLAY INVISIBLE (-3250 3700);
FORCEPROP 1 LAST HDL_TAP TRUE
J 0
(-2925 3525);
DISPLAY 0.872340 (-2925 3525);
DISPLAY INVISIBLE (-2925 3525);
FORCEPROP 1 LAST PATH I210
J 0
(-3252 3650);
DISPLAY 0.872340 (-3252 3650);
PAINT GREEN (-3252 3650);
DISPLAY INVISIBLE (-3252 3650);
FORCEADD TAP..1
(-3250 3300);
FORCEPROP 3 LASTPIN (-3300 3300) SIG_NAME M_B_CPU1_SB_DQS_DN<8>
J 0
(-3290 3310);
DISPLAY 0.659574 (-3290 3310);
PAINT MONO (-3290 3310);
DISPLAY INVISIBLE (-3290 3310);
FORCEPROP 1 LASTPIN (-3300 3300) BN 8
J 0
(-3312 3308);
DISPLAY 0.489362 (-3312 3308);
PAINT GREEN (-3312 3308);
FORCEPROP 2 LAST CDS_LIB mstr_standard
J 0
(-3250 3300);
DISPLAY 0.723404 (-3250 3300);
PAINT MONO (-3250 3300);
DISPLAY INVISIBLE (-3250 3300);
FORCEPROP 1 LAST BODY_TYPE PLUMBING
J 0
(-3250 3350);
DISPLAY 0.872340 (-3250 3350);
PAINT GREEN (-3250 3350);
DISPLAY INVISIBLE (-3250 3350);
FORCEPROP 1 LAST HDL_TAP TRUE
J 0
(-2925 3175);
DISPLAY 0.872340 (-2925 3175);
DISPLAY INVISIBLE (-2925 3175);
FORCEPROP 1 LAST PATH I211
J 0
(-3252 3300);
DISPLAY 0.872340 (-3252 3300);
PAINT GREEN (-3252 3300);
DISPLAY INVISIBLE (-3252 3300);
FORCEADD TAP..1
(-3250 3400);
FORCEPROP 3 LASTPIN (-3300 3400) SIG_NAME M_B_CPU1_SB_DQS_DN<9>
J 0
(-3290 3410);
DISPLAY 0.659574 (-3290 3410);
PAINT MONO (-3290 3410);
DISPLAY INVISIBLE (-3290 3410);
FORCEPROP 1 LASTPIN (-3300 3400) BN 9
J 0
(-3312 3408);
DISPLAY 0.489362 (-3312 3408);
PAINT GREEN (-3312 3408);
FORCEPROP 2 LAST CDS_LIB mstr_standard
J 0
(-3250 3400);
DISPLAY 0.723404 (-3250 3400);
PAINT MONO (-3250 3400);
DISPLAY INVISIBLE (-3250 3400);
FORCEPROP 1 LAST BODY_TYPE PLUMBING
J 0
(-3250 3450);
DISPLAY 0.872340 (-3250 3450);
PAINT GREEN (-3250 3450);
DISPLAY INVISIBLE (-3250 3450);
FORCEPROP 1 LAST HDL_TAP TRUE
J 0
(-2925 3275);
DISPLAY 0.872340 (-2925 3275);
DISPLAY INVISIBLE (-2925 3275);
FORCEPROP 1 LAST PATH I212
J 0
(-3252 3400);
DISPLAY 0.872340 (-3252 3400);
PAINT GREEN (-3252 3400);
DISPLAY INVISIBLE (-3252 3400);
FORCEADD TAP..1
(-3250 3200);
FORCEPROP 3 LASTPIN (-3300 3200) SIG_NAME M_B_CPU1_SB_DQS_DN<7>
J 0
(-3290 3210);
DISPLAY 0.659574 (-3290 3210);
PAINT MONO (-3290 3210);
DISPLAY INVISIBLE (-3290 3210);
FORCEPROP 1 LASTPIN (-3300 3200) BN 7
J 0
(-3312 3208);
DISPLAY 0.489362 (-3312 3208);
PAINT GREEN (-3312 3208);
FORCEPROP 2 LAST CDS_LIB mstr_standard
J 0
(-3250 3200);
DISPLAY 0.723404 (-3250 3200);
PAINT MONO (-3250 3200);
DISPLAY INVISIBLE (-3250 3200);
FORCEPROP 1 LAST BODY_TYPE PLUMBING
J 0
(-3250 3250);
DISPLAY 0.872340 (-3250 3250);
PAINT GREEN (-3250 3250);
DISPLAY INVISIBLE (-3250 3250);
FORCEPROP 1 LAST HDL_TAP TRUE
J 0
(-2925 3075);
DISPLAY 0.872340 (-2925 3075);
DISPLAY INVISIBLE (-2925 3075);
FORCEPROP 1 LAST PATH I213
J 0
(-3252 3200);
DISPLAY 0.872340 (-3252 3200);
PAINT GREEN (-3252 3200);
DISPLAY INVISIBLE (-3252 3200);
FORCEADD TAP..1
(-3250 3100);
FORCEPROP 3 LASTPIN (-3300 3100) SIG_NAME M_B_CPU1_SB_DQS_DN<6>
J 0
(-3290 3110);
DISPLAY 0.659574 (-3290 3110);
PAINT MONO (-3290 3110);
DISPLAY INVISIBLE (-3290 3110);
FORCEPROP 1 LASTPIN (-3300 3100) BN 6
J 0
(-3312 3108);
DISPLAY 0.489362 (-3312 3108);
PAINT GREEN (-3312 3108);
FORCEPROP 2 LAST CDS_LIB mstr_standard
J 0
(-3250 3100);
DISPLAY 0.723404 (-3250 3100);
PAINT MONO (-3250 3100);
DISPLAY INVISIBLE (-3250 3100);
FORCEPROP 1 LAST BODY_TYPE PLUMBING
J 0
(-3250 3150);
DISPLAY 0.872340 (-3250 3150);
PAINT GREEN (-3250 3150);
DISPLAY INVISIBLE (-3250 3150);
FORCEPROP 1 LAST HDL_TAP TRUE
J 0
(-2925 2975);
DISPLAY 0.872340 (-2925 2975);
DISPLAY INVISIBLE (-2925 2975);
FORCEPROP 1 LAST PATH I214
J 0
(-3252 3100);
DISPLAY 0.872340 (-3252 3100);
PAINT GREEN (-3252 3100);
DISPLAY INVISIBLE (-3252 3100);
FORCEADD TAP..1
(-3450 3900);
FORCEPROP 3 LASTPIN (-3500 3900) SIG_NAME M_B_CPU1_SA_DQS_DP<3>
J 0
(-3490 3910);
DISPLAY 0.659574 (-3490 3910);
PAINT MONO (-3490 3910);
DISPLAY INVISIBLE (-3490 3910);
FORCEPROP 1 LASTPIN (-3500 3900) BN 3
J 0
(-3512 3908);
DISPLAY 0.489362 (-3512 3908);
PAINT GREEN (-3512 3908);
FORCEPROP 2 LAST CDS_LIB mstr_standard
J 0
(-3450 3900);
DISPLAY 0.723404 (-3450 3900);
PAINT MONO (-3450 3900);
DISPLAY INVISIBLE (-3450 3900);
FORCEPROP 1 LAST BODY_TYPE PLUMBING
J 0
(-3450 3950);
DISPLAY 0.872340 (-3450 3950);
PAINT GREEN (-3450 3950);
DISPLAY INVISIBLE (-3450 3950);
FORCEPROP 1 LAST HDL_TAP TRUE
J 0
(-3125 3775);
DISPLAY 0.872340 (-3125 3775);
DISPLAY INVISIBLE (-3125 3775);
FORCEPROP 1 LAST PATH I215
J 0
(-3452 3900);
DISPLAY 0.872340 (-3452 3900);
PAINT GREEN (-3452 3900);
DISPLAY INVISIBLE (-3452 3900);
FORCEADD TAP..1
(-3450 4000);
FORCEPROP 3 LASTPIN (-3500 4000) SIG_NAME M_B_CPU1_SA_DQS_DP<4>
J 0
(-3490 4010);
DISPLAY 0.659574 (-3490 4010);
PAINT MONO (-3490 4010);
DISPLAY INVISIBLE (-3490 4010);
FORCEPROP 1 LASTPIN (-3500 4000) BN 4
J 0
(-3512 4008);
DISPLAY 0.489362 (-3512 4008);
PAINT GREEN (-3512 4008);
FORCEPROP 2 LAST CDS_LIB mstr_standard
J 0
(-3450 4000);
DISPLAY 0.723404 (-3450 4000);
PAINT MONO (-3450 4000);
DISPLAY INVISIBLE (-3450 4000);
FORCEPROP 1 LAST BODY_TYPE PLUMBING
J 0
(-3450 4050);
DISPLAY 0.872340 (-3450 4050);
PAINT GREEN (-3450 4050);
DISPLAY INVISIBLE (-3450 4050);
FORCEPROP 1 LAST HDL_TAP TRUE
J 0
(-3125 3875);
DISPLAY 0.872340 (-3125 3875);
DISPLAY INVISIBLE (-3125 3875);
FORCEPROP 1 LAST PATH I216
J 0
(-3452 4000);
DISPLAY 0.872340 (-3452 4000);
PAINT GREEN (-3452 4000);
DISPLAY INVISIBLE (-3452 4000);
FORCEADD TAP..1
(-3450 3800);
FORCEPROP 3 LASTPIN (-3500 3800) SIG_NAME M_B_CPU1_SA_DQS_DP<2>
J 0
(-3490 3810);
DISPLAY 0.659574 (-3490 3810);
PAINT MONO (-3490 3810);
DISPLAY INVISIBLE (-3490 3810);
FORCEPROP 1 LASTPIN (-3500 3800) BN 2
J 0
(-3512 3808);
DISPLAY 0.489362 (-3512 3808);
PAINT GREEN (-3512 3808);
FORCEPROP 2 LAST CDS_LIB mstr_standard
J 0
(-3450 3800);
DISPLAY 0.723404 (-3450 3800);
PAINT MONO (-3450 3800);
DISPLAY INVISIBLE (-3450 3800);
FORCEPROP 1 LAST BODY_TYPE PLUMBING
J 0
(-3450 3850);
DISPLAY 0.872340 (-3450 3850);
PAINT GREEN (-3450 3850);
DISPLAY INVISIBLE (-3450 3850);
FORCEPROP 1 LAST HDL_TAP TRUE
J 0
(-3125 3675);
DISPLAY 0.872340 (-3125 3675);
DISPLAY INVISIBLE (-3125 3675);
FORCEPROP 1 LAST PATH I217
J 0
(-3452 3800);
DISPLAY 0.872340 (-3452 3800);
PAINT GREEN (-3452 3800);
DISPLAY INVISIBLE (-3452 3800);
FORCEADD TAP..1
(-3450 3700);
FORCEPROP 3 LASTPIN (-3500 3700) SIG_NAME M_B_CPU1_SA_DQS_DP<1>
J 0
(-3490 3710);
DISPLAY 0.659574 (-3490 3710);
PAINT MONO (-3490 3710);
DISPLAY INVISIBLE (-3490 3710);
FORCEPROP 1 LASTPIN (-3500 3700) BN 1
J 0
(-3512 3708);
DISPLAY 0.489362 (-3512 3708);
PAINT GREEN (-3512 3708);
FORCEPROP 2 LAST CDS_LIB mstr_standard
J 0
(-3450 3700);
DISPLAY 0.723404 (-3450 3700);
PAINT MONO (-3450 3700);
DISPLAY INVISIBLE (-3450 3700);
FORCEPROP 1 LAST BODY_TYPE PLUMBING
J 0
(-3450 3750);
DISPLAY 0.872340 (-3450 3750);
PAINT GREEN (-3450 3750);
DISPLAY INVISIBLE (-3450 3750);
FORCEPROP 1 LAST HDL_TAP TRUE
J 0
(-3125 3575);
DISPLAY 0.872340 (-3125 3575);
DISPLAY INVISIBLE (-3125 3575);
FORCEPROP 1 LAST PATH I218
J 0
(-3452 3700);
DISPLAY 0.872340 (-3452 3700);
PAINT GREEN (-3452 3700);
DISPLAY INVISIBLE (-3452 3700);
FORCEADD TAP..1
(-3450 3600);
FORCEPROP 3 LASTPIN (-3500 3600) SIG_NAME M_B_CPU1_SA_DQS_DP<0>
J 0
(-3490 3610);
DISPLAY 0.659574 (-3490 3610);
PAINT MONO (-3490 3610);
DISPLAY INVISIBLE (-3490 3610);
FORCEPROP 1 LASTPIN (-3500 3600) BN 0
J 0
(-3512 3608);
DISPLAY 0.489362 (-3512 3608);
PAINT GREEN (-3512 3608);
FORCEPROP 2 LAST CDS_LIB mstr_standard
J 0
(-3450 3600);
DISPLAY 0.723404 (-3450 3600);
PAINT MONO (-3450 3600);
DISPLAY INVISIBLE (-3450 3600);
FORCEPROP 1 LAST BODY_TYPE PLUMBING
J 0
(-3450 3650);
DISPLAY 0.872340 (-3450 3650);
PAINT GREEN (-3450 3650);
DISPLAY INVISIBLE (-3450 3650);
FORCEPROP 1 LAST HDL_TAP TRUE
J 0
(-3125 3475);
DISPLAY 0.872340 (-3125 3475);
DISPLAY INVISIBLE (-3125 3475);
FORCEPROP 1 LAST PATH I219
J 0
(-3452 3600);
DISPLAY 0.872340 (-3452 3600);
PAINT GREEN (-3452 3600);
DISPLAY INVISIBLE (-3452 3600);
FORCEADD SCONN288_DDR506112002KQ..1
(-6925 3775);
FORCEPROP 1 LAST LOCATION J26
J 0
(-7375 5850);
DISPLAY 0.468085 (-7375 5850);
PAINT SKYBLUE (-7375 5850);
FORCEPROP 0 LAST $SEC 1
J 0
(-7375 6000);
DISPLAY 0.680851 (-7375 6000);
PAINT MONO (-7375 6000);
DISPLAY INVISIBLE (-7375 6000);
FORCEPROP 2 LAST CDS_SEC 1
J 0
(-7375 6000);
DISPLAY 1.021277 (-7375 6000);
DISPLAY INVISIBLE (-7375 6000);
FORCEPROP 0 LASTPIN (-7525 3175) $PN 62
J 2
(-7535 3185);
DISPLAY 0.680851 (-7535 3185);
PAINT MONO (-7535 3185);
FORCEPROP 0 LASTPIN (-7525 5225) $PN 66
J 2
(-7535 5235);
DISPLAY 0.680851 (-7535 5235);
PAINT MONO (-7535 5235);
FORCEPROP 0 LASTPIN (-7525 4825) $PN 76
J 2
(-7535 4835);
DISPLAY 0.680851 (-7535 4835);
PAINT MONO (-7535 4835);
FORCEPROP 0 LASTPIN (-7525 5275) $PN 211
J 2
(-7535 5285);
DISPLAY 0.680851 (-7535 5285);
PAINT MONO (-7535 5285);
FORCEPROP 0 LASTPIN (-7525 4875) $PN 221
J 2
(-7535 4885);
DISPLAY 0.680851 (-7535 4885);
PAINT MONO (-7535 4885);
FORCEPROP 0 LASTPIN (-7525 5325) $PN 68
J 2
(-7535 5335);
DISPLAY 0.680851 (-7535 5335);
PAINT MONO (-7535 5335);
FORCEPROP 0 LASTPIN (-7525 4925) $PN 78
J 2
(-7535 4935);
DISPLAY 0.680851 (-7535 4935);
PAINT MONO (-7535 4935);
FORCEPROP 0 LASTPIN (-7525 5375) $PN 213
J 2
(-7535 5385);
DISPLAY 0.680851 (-7535 5385);
PAINT MONO (-7535 5385);
FORCEPROP 0 LASTPIN (-7525 4975) $PN 223
J 2
(-7535 4985);
DISPLAY 0.680851 (-7535 4985);
PAINT MONO (-7535 4985);
FORCEPROP 0 LASTPIN (-7525 5425) $PN 70
J 2
(-7535 5435);
DISPLAY 0.680851 (-7535 5435);
PAINT MONO (-7535 5435);
FORCEPROP 0 LASTPIN (-7525 5025) $PN 80
J 2
(-7535 5035);
DISPLAY 0.680851 (-7535 5035);
PAINT MONO (-7535 5035);
FORCEPROP 0 LASTPIN (-7525 5475) $PN 215
J 2
(-7535 5485);
DISPLAY 0.680851 (-7535 5485);
PAINT MONO (-7535 5485);
FORCEPROP 0 LASTPIN (-7525 5075) $PN 225
J 2
(-7535 5085);
DISPLAY 0.680851 (-7535 5085);
PAINT MONO (-7535 5085);
FORCEPROP 0 LASTPIN (-7525 5525) $PN 72
J 2
(-7535 5535);
DISPLAY 0.680851 (-7535 5535);
PAINT MONO (-7535 5535);
FORCEPROP 0 LASTPIN (-7525 5125) $PN 82
J 2
(-7535 5135);
DISPLAY 0.680851 (-7535 5135);
PAINT MONO (-7535 5135);
FORCEPROP 0 LASTPIN (-7525 3775) $PN 51
J 2
(-7535 3785);
DISPLAY 0.680851 (-7535 3785);
PAINT MONO (-7535 3785);
FORCEPROP 0 LASTPIN (-7525 3325) $PN 96
J 2
(-7535 3335);
DISPLAY 0.680851 (-7535 3335);
PAINT MONO (-7535 3335);
FORCEPROP 0 LASTPIN (-7525 3825) $PN 53
J 2
(-7535 3835);
DISPLAY 0.680851 (-7535 3835);
PAINT MONO (-7535 3835);
FORCEPROP 0 LASTPIN (-7525 3375) $PN 98
J 2
(-7535 3385);
DISPLAY 0.680851 (-7535 3385);
PAINT MONO (-7535 3385);
FORCEPROP 0 LASTPIN (-7525 3875) $PN 196
J 2
(-7535 3885);
DISPLAY 0.680851 (-7535 3885);
PAINT MONO (-7535 3885);
FORCEPROP 0 LASTPIN (-7525 3425) $PN 241
J 2
(-7535 3435);
DISPLAY 0.680851 (-7535 3435);
PAINT MONO (-7535 3435);
FORCEPROP 0 LASTPIN (-7525 3925) $PN 198
J 2
(-7535 3935);
DISPLAY 0.680851 (-7535 3935);
PAINT MONO (-7535 3935);
FORCEPROP 0 LASTPIN (-7525 3475) $PN 243
J 2
(-7535 3485);
DISPLAY 0.680851 (-7535 3485);
PAINT MONO (-7535 3485);
FORCEPROP 0 LASTPIN (-7525 3975) $PN 58
J 2
(-7535 3985);
DISPLAY 0.680851 (-7535 3985);
PAINT MONO (-7535 3985);
FORCEPROP 0 LASTPIN (-7525 3525) $PN 89
J 2
(-7535 3535);
DISPLAY 0.680851 (-7535 3535);
PAINT MONO (-7535 3535);
FORCEPROP 0 LASTPIN (-7525 4025) $PN 60
J 2
(-7535 4035);
DISPLAY 0.680851 (-7535 4035);
PAINT MONO (-7535 4035);
FORCEPROP 0 LASTPIN (-7525 3575) $PN 91
J 2
(-7535 3585);
DISPLAY 0.680851 (-7535 3585);
PAINT MONO (-7535 3585);
FORCEPROP 0 LASTPIN (-7525 4075) $PN 203
J 2
(-7535 4085);
DISPLAY 0.680851 (-7535 4085);
PAINT MONO (-7535 4085);
FORCEPROP 0 LASTPIN (-7525 3625) $PN 234
J 2
(-7535 3635);
DISPLAY 0.680851 (-7535 3635);
PAINT MONO (-7535 3635);
FORCEPROP 0 LASTPIN (-7525 4125) $PN 205
J 2
(-7535 4135);
DISPLAY 0.680851 (-7535 4135);
PAINT MONO (-7535 4135);
FORCEPROP 0 LASTPIN (-7525 3675) $PN 236
J 2
(-7535 3685);
DISPLAY 0.680851 (-7535 3685);
PAINT MONO (-7535 3685);
FORCEPROP 0 LASTPIN (-7525 4225) $PN 218
J 2
(-7535 4235);
DISPLAY 0.680851 (-7535 4235);
PAINT MONO (-7535 4235);
FORCEPROP 0 LASTPIN (-7525 4275) $PN 217
J 2
(-7535 4285);
DISPLAY 0.680851 (-7535 4285);
PAINT MONO (-7535 4285);
FORCEPROP 0 LASTPIN (-7525 4525) $PN 64
J 2
(-7535 4535);
DISPLAY 0.680851 (-7535 4535);
PAINT MONO (-7535 4535);
FORCEPROP 0 LASTPIN (-7525 4375) $PN 84
J 2
(-7535 4385);
DISPLAY 0.680851 (-7535 4385);
PAINT MONO (-7535 4385);
FORCEPROP 0 LASTPIN (-7525 4575) $PN 209
J 2
(-7535 4585);
DISPLAY 0.680851 (-7535 4585);
PAINT MONO (-7535 4585);
FORCEPROP 0 LASTPIN (-7525 4425) $PN 229
J 2
(-7535 4435);
DISPLAY 0.680851 (-7535 4435);
PAINT MONO (-7535 4435);
FORCEPROP 0 LASTPIN (-6325 3975) $PN 7
J 0
(-6315 3985);
DISPLAY 0.680851 (-6315 3985);
PAINT MONO (-6315 3985);
FORCEPROP 0 LASTPIN (-6325 2325) $PN 100
J 0
(-6315 2335);
DISPLAY 0.680851 (-6315 2335);
PAINT MONO (-6315 2335);
FORCEPROP 0 LASTPIN (-6325 4025) $PN 9
J 0
(-6315 4035);
DISPLAY 0.680851 (-6315 4035);
PAINT MONO (-6315 4035);
FORCEPROP 0 LASTPIN (-6325 2375) $PN 102
J 0
(-6315 2385);
DISPLAY 0.680851 (-6315 2385);
PAINT MONO (-6315 2385);
FORCEPROP 0 LASTPIN (-6325 4075) $PN 152
J 0
(-6315 4085);
DISPLAY 0.680851 (-6315 4085);
PAINT MONO (-6315 4085);
FORCEPROP 0 LASTPIN (-6325 2425) $PN 245
J 0
(-6315 2435);
DISPLAY 0.680851 (-6315 2435);
PAINT MONO (-6315 2435);
FORCEPROP 0 LASTPIN (-6325 4125) $PN 154
J 0
(-6315 4135);
DISPLAY 0.680851 (-6315 4135);
PAINT MONO (-6315 4135);
FORCEPROP 0 LASTPIN (-6325 2475) $PN 247
J 0
(-6315 2485);
DISPLAY 0.680851 (-6315 2485);
PAINT MONO (-6315 2485);
FORCEPROP 0 LASTPIN (-6325 4175) $PN 14
J 0
(-6315 4185);
DISPLAY 0.680851 (-6315 4185);
PAINT MONO (-6315 4185);
FORCEPROP 0 LASTPIN (-6325 2525) $PN 107
J 0
(-6315 2535);
DISPLAY 0.680851 (-6315 2535);
PAINT MONO (-6315 2535);
FORCEPROP 0 LASTPIN (-6325 4225) $PN 16
J 0
(-6315 4235);
DISPLAY 0.680851 (-6315 4235);
PAINT MONO (-6315 4235);
FORCEPROP 0 LASTPIN (-6325 2575) $PN 109
J 0
(-6315 2585);
DISPLAY 0.680851 (-6315 2585);
PAINT MONO (-6315 2585);
FORCEPROP 0 LASTPIN (-6325 4275) $PN 159
J 0
(-6315 4285);
DISPLAY 0.680851 (-6315 4285);
PAINT MONO (-6315 4285);
FORCEPROP 0 LASTPIN (-6325 2625) $PN 252
J 0
(-6315 2635);
DISPLAY 0.680851 (-6315 2635);
PAINT MONO (-6315 2635);
FORCEPROP 0 LASTPIN (-6325 4325) $PN 161
J 0
(-6315 4335);
DISPLAY 0.680851 (-6315 4335);
PAINT MONO (-6315 4335);
FORCEPROP 0 LASTPIN (-6325 2675) $PN 254
J 0
(-6315 2685);
DISPLAY 0.680851 (-6315 2685);
PAINT MONO (-6315 2685);
FORCEPROP 0 LASTPIN (-6325 4375) $PN 18
J 0
(-6315 4385);
DISPLAY 0.680851 (-6315 4385);
PAINT MONO (-6315 4385);
FORCEPROP 0 LASTPIN (-6325 2725) $PN 111
J 0
(-6315 2735);
DISPLAY 0.680851 (-6315 2735);
PAINT MONO (-6315 2735);
FORCEPROP 0 LASTPIN (-6325 4425) $PN 20
J 0
(-6315 4435);
DISPLAY 0.680851 (-6315 4435);
PAINT MONO (-6315 4435);
FORCEPROP 0 LASTPIN (-6325 2775) $PN 113
J 0
(-6315 2785);
DISPLAY 0.680851 (-6315 2785);
PAINT MONO (-6315 2785);
FORCEPROP 0 LASTPIN (-6325 4475) $PN 163
J 0
(-6315 4485);
DISPLAY 0.680851 (-6315 4485);
PAINT MONO (-6315 4485);
FORCEPROP 0 LASTPIN (-6325 2825) $PN 256
J 0
(-6315 2835);
DISPLAY 0.680851 (-6315 2835);
PAINT MONO (-6315 2835);
FORCEPROP 0 LASTPIN (-6325 4525) $PN 165
J 0
(-6315 4535);
DISPLAY 0.680851 (-6315 4535);
PAINT MONO (-6315 4535);
FORCEPROP 0 LASTPIN (-6325 2875) $PN 258
J 0
(-6315 2885);
DISPLAY 0.680851 (-6315 2885);
PAINT MONO (-6315 2885);
FORCEPROP 0 LASTPIN (-6325 4575) $PN 25
J 0
(-6315 4585);
DISPLAY 0.680851 (-6315 4585);
PAINT MONO (-6315 4585);
FORCEPROP 0 LASTPIN (-6325 2925) $PN 118
J 0
(-6315 2935);
DISPLAY 0.680851 (-6315 2935);
PAINT MONO (-6315 2935);
FORCEPROP 0 LASTPIN (-6325 4625) $PN 27
J 0
(-6315 4635);
DISPLAY 0.680851 (-6315 4635);
PAINT MONO (-6315 4635);
FORCEPROP 0 LASTPIN (-6325 2975) $PN 120
J 0
(-6315 2985);
DISPLAY 0.680851 (-6315 2985);
PAINT MONO (-6315 2985);
FORCEPROP 0 LASTPIN (-6325 4675) $PN 170
J 0
(-6315 4685);
DISPLAY 0.680851 (-6315 4685);
PAINT MONO (-6315 4685);
FORCEPROP 0 LASTPIN (-6325 3025) $PN 263
J 0
(-6315 3035);
DISPLAY 0.680851 (-6315 3035);
PAINT MONO (-6315 3035);
FORCEPROP 0 LASTPIN (-6325 4725) $PN 172
J 0
(-6315 4735);
DISPLAY 0.680851 (-6315 4735);
PAINT MONO (-6315 4735);
FORCEPROP 0 LASTPIN (-6325 3075) $PN 265
J 0
(-6315 3085);
DISPLAY 0.680851 (-6315 3085);
PAINT MONO (-6315 3085);
FORCEPROP 0 LASTPIN (-6325 4775) $PN 29
J 0
(-6315 4785);
DISPLAY 0.680851 (-6315 4785);
PAINT MONO (-6315 4785);
FORCEPROP 0 LASTPIN (-6325 3125) $PN 122
J 0
(-6315 3135);
DISPLAY 0.680851 (-6315 3135);
PAINT MONO (-6315 3135);
FORCEPROP 0 LASTPIN (-6325 4825) $PN 31
J 0
(-6315 4835);
DISPLAY 0.680851 (-6315 4835);
PAINT MONO (-6315 4835);
FORCEPROP 0 LASTPIN (-6325 3175) $PN 124
J 0
(-6315 3185);
DISPLAY 0.680851 (-6315 3185);
PAINT MONO (-6315 3185);
FORCEPROP 0 LASTPIN (-6325 4875) $PN 174
J 0
(-6315 4885);
DISPLAY 0.680851 (-6315 4885);
PAINT MONO (-6315 4885);
FORCEPROP 0 LASTPIN (-6325 3225) $PN 267
J 0
(-6315 3235);
DISPLAY 0.680851 (-6315 3235);
PAINT MONO (-6315 3235);
FORCEPROP 0 LASTPIN (-6325 4925) $PN 176
J 0
(-6315 4935);
DISPLAY 0.680851 (-6315 4935);
PAINT MONO (-6315 4935);
FORCEPROP 0 LASTPIN (-6325 3275) $PN 269
J 0
(-6315 3285);
DISPLAY 0.680851 (-6315 3285);
PAINT MONO (-6315 3285);
FORCEPROP 0 LASTPIN (-6325 4975) $PN 36
J 0
(-6315 4985);
DISPLAY 0.680851 (-6315 4985);
PAINT MONO (-6315 4985);
FORCEPROP 0 LASTPIN (-6325 3325) $PN 129
J 0
(-6315 3335);
DISPLAY 0.680851 (-6315 3335);
PAINT MONO (-6315 3335);
FORCEPROP 0 LASTPIN (-6325 5025) $PN 38
J 0
(-6315 5035);
DISPLAY 0.680851 (-6315 5035);
PAINT MONO (-6315 5035);
FORCEPROP 0 LASTPIN (-6325 3375) $PN 131
J 0
(-6315 3385);
DISPLAY 0.680851 (-6315 3385);
PAINT MONO (-6315 3385);
FORCEPROP 0 LASTPIN (-6325 5075) $PN 181
J 0
(-6315 5085);
DISPLAY 0.680851 (-6315 5085);
PAINT MONO (-6315 5085);
FORCEPROP 0 LASTPIN (-6325 3425) $PN 274
J 0
(-6315 3435);
DISPLAY 0.680851 (-6315 3435);
PAINT MONO (-6315 3435);
FORCEPROP 0 LASTPIN (-6325 5125) $PN 183
J 0
(-6315 5135);
DISPLAY 0.680851 (-6315 5135);
PAINT MONO (-6315 5135);
FORCEPROP 0 LASTPIN (-6325 3475) $PN 276
J 0
(-6315 3485);
DISPLAY 0.680851 (-6315 3485);
PAINT MONO (-6315 3485);
FORCEPROP 0 LASTPIN (-6325 5175) $PN 40
J 0
(-6315 5185);
DISPLAY 0.680851 (-6315 5185);
PAINT MONO (-6315 5185);
FORCEPROP 0 LASTPIN (-6325 3525) $PN 133
J 0
(-6315 3535);
DISPLAY 0.680851 (-6315 3535);
PAINT MONO (-6315 3535);
FORCEPROP 0 LASTPIN (-6325 5225) $PN 42
J 0
(-6315 5235);
DISPLAY 0.680851 (-6315 5235);
PAINT MONO (-6315 5235);
FORCEPROP 0 LASTPIN (-6325 3575) $PN 135
J 0
(-6315 3585);
DISPLAY 0.680851 (-6315 3585);
PAINT MONO (-6315 3585);
FORCEPROP 0 LASTPIN (-6325 5275) $PN 185
J 0
(-6315 5285);
DISPLAY 0.680851 (-6315 5285);
PAINT MONO (-6315 5285);
FORCEPROP 0 LASTPIN (-6325 3625) $PN 278
J 0
(-6315 3635);
DISPLAY 0.680851 (-6315 3635);
PAINT MONO (-6315 3635);
FORCEPROP 0 LASTPIN (-6325 5325) $PN 187
J 0
(-6315 5335);
DISPLAY 0.680851 (-6315 5335);
PAINT MONO (-6315 5335);
FORCEPROP 0 LASTPIN (-6325 3675) $PN 280
J 0
(-6315 3685);
DISPLAY 0.680851 (-6315 3685);
PAINT MONO (-6315 3685);
FORCEPROP 0 LASTPIN (-6325 5375) $PN 47
J 0
(-6315 5385);
DISPLAY 0.680851 (-6315 5385);
PAINT MONO (-6315 5385);
FORCEPROP 0 LASTPIN (-6325 3725) $PN 140
J 0
(-6315 3735);
DISPLAY 0.680851 (-6315 3735);
PAINT MONO (-6315 3735);
FORCEPROP 0 LASTPIN (-6325 5425) $PN 49
J 0
(-6315 5435);
DISPLAY 0.680851 (-6315 5435);
PAINT MONO (-6315 5435);
FORCEPROP 0 LASTPIN (-6325 3775) $PN 142
J 0
(-6315 3785);
DISPLAY 0.680851 (-6315 3785);
PAINT MONO (-6315 3785);
FORCEPROP 0 LASTPIN (-6325 5475) $PN 192
J 0
(-6315 5485);
DISPLAY 0.680851 (-6315 5485);
PAINT MONO (-6315 5485);
FORCEPROP 0 LASTPIN (-6325 3825) $PN 285
J 0
(-6315 3835);
DISPLAY 0.680851 (-6315 3835);
PAINT MONO (-6315 3835);
FORCEPROP 0 LASTPIN (-6325 5525) $PN 194
J 0
(-6315 5535);
DISPLAY 0.680851 (-6315 5535);
PAINT MONO (-6315 5535);
FORCEPROP 0 LASTPIN (-6325 3875) $PN 287
J 0
(-6315 3885);
DISPLAY 0.680851 (-6315 3885);
PAINT MONO (-6315 3885);
FORCEPROP 0 LASTPIN (-7525 3025) $PN 148
J 2
(-7535 3035);
DISPLAY 0.680851 (-7535 3035);
PAINT MONO (-7535 3035);
FORCEPROP 0 LASTPIN (-7525 2925) $PN 4
J 2
(-7535 2935);
DISPLAY 0.680851 (-7535 2935);
PAINT MONO (-7535 2935);
FORCEPROP 0 LASTPIN (-7525 2975) $PN 5
J 2
(-7535 2985);
DISPLAY 0.680851 (-7535 2985);
PAINT MONO (-7535 2985);
FORCEPROP 0 LASTPIN (-7525 2125) $PN 86
J 2
(-7535 2135);
DISPLAY 0.680851 (-7535 2135);
PAINT MONO (-7535 2135);
FORCEPROP 0 LASTPIN (-7525 2075) $PN 87
J 2
(-7535 2085);
DISPLAY 0.680851 (-7535 2085);
PAINT MONO (-7535 2085);
FORCEPROP 0 LASTPIN (-7525 4725) $PN 74
J 2
(-7535 4735);
DISPLAY 0.680851 (-7535 4735);
PAINT MONO (-7535 4735);
FORCEPROP 0 LASTPIN (-7525 4675) $PN 227
J 2
(-7535 4685);
DISPLAY 0.680851 (-7535 4685);
PAINT MONO (-7535 4685);
FORCEPROP 0 LASTPIN (-7525 2675) $PN 147
J 2
(-7535 2685);
DISPLAY 0.680851 (-7535 2685);
PAINT MONO (-7535 2685);
FORCEPROP 0 LASTPIN (-7525 3225) $PN 207
J 2
(-7535 3235);
DISPLAY 0.680851 (-7535 3235);
PAINT MONO (-7535 3235);
FORCEPROP 0 LASTPIN (-7525 2275) $PN 2
J 2
(-7535 2285);
DISPLAY 0.680851 (-7535 2285);
PAINT MONO (-7535 2285);
FORCEPROP 0 LASTPIN (-7525 2325) $PN 144
J 2
(-7535 2335);
DISPLAY 0.680851 (-7535 2335);
PAINT MONO (-7535 2335);
FORCEPROP 0 LASTPIN (-7525 2375) $PN 149
J 2
(-7535 2385);
DISPLAY 0.680851 (-7535 2385);
PAINT MONO (-7535 2385);
FORCEPROP 0 LASTPIN (-7525 2425) $PN 150
J 2
(-7535 2435);
DISPLAY 0.680851 (-7535 2435);
PAINT MONO (-7535 2435);
FORCEPROP 0 LASTPIN (-7525 2475) $PN 220
J 2
(-7535 2485);
DISPLAY 0.680851 (-7535 2485);
PAINT MONO (-7535 2485);
FORCEPROP 0 LASTPIN (-7525 2525) $PN 231
J 2
(-7535 2535);
DISPLAY 0.680851 (-7535 2535);
PAINT MONO (-7535 2535);
FORCEPROP 0 LASTPIN (-7525 2575) $PN 232
J 2
(-7535 2585);
DISPLAY 0.680851 (-7535 2585);
PAINT MONO (-7535 2585);
FORCEPROP 0 LASTPIN (-7525 3075) $PN 3
J 2
(-7535 3085);
DISPLAY 0.680851 (-7535 3085);
PAINT MONO (-7535 3085);
FORCEPROP 2 LAST PART_TYPE SMLF
J 0
(-7375 5950);
DISPLAY 1.021277 (-7375 5950);
FORCEPROP 2 LAST VALUE SCONN288_DDR506112002KQ
J 0
(-7375 5900);
DISPLAY 0.489362 (-7375 5900);
PAINT SKYBLUE (-7375 5900);
FORCEPROP 1 LAST MATERIAL IO
J 0
(-7375 5700);
DISPLAY 0.468085 (-7375 5700);
PAINT SKYBLUE (-7375 5700);
FORCEPROP 1 LAST CDS_LMAN_SYM_OUTLINE -450,1900,450,-1850
J 0
(-6925 3775);
DISPLAY 0.468085 (-6925 3775);
PAINT GREEN (-6925 3775);
DISPLAY INVISIBLE (-6925 3775);
FORCEPROP 1 LAST NEEDS_NO_SIZE TRUE
J 0
(-6925 3775);
DISPLAY 0.723404 (-6925 3775);
PAINT GREEN (-6925 3775);
DISPLAY INVISIBLE (-6925 3775);
FORCEPROP 2 LAST CDS_LIB pure_quanta
J 0
(-6925 3775);
DISPLAY INVISIBLE (-6925 3775);
FORCEPROP 1 LAST PATH I22
J 0
(-6925 3775);
DISPLAY 0.723404 (-6925 3775);
PAINT GREEN (-6925 3775);
DISPLAY INVISIBLE (-6925 3775);
FORCEPROP 1 LAST PART_NUMBER DFHST8FS479
J 0
(-7375 5775);
DISPLAY 0.468085 (-7375 5775);
PAINT SKYBLUE (-7375 5775);
DISPLAY INVISIBLE (-7375 5775);
FORCEADD TAP..1
(-3450 3350);
FORCEPROP 3 LASTPIN (-3500 3350) SIG_NAME M_B_CPU1_SB_DQS_DP<8>
J 0
(-3490 3360);
DISPLAY 0.659574 (-3490 3360);
PAINT MONO (-3490 3360);
DISPLAY INVISIBLE (-3490 3360);
FORCEPROP 1 LASTPIN (-3500 3350) BN 8
J 0
(-3512 3358);
DISPLAY 0.489362 (-3512 3358);
PAINT GREEN (-3512 3358);
FORCEPROP 2 LAST CDS_LIB mstr_standard
J 0
(-3450 3350);
DISPLAY 0.723404 (-3450 3350);
PAINT MONO (-3450 3350);
DISPLAY INVISIBLE (-3450 3350);
FORCEPROP 1 LAST BODY_TYPE PLUMBING
J 0
(-3450 3400);
DISPLAY 0.872340 (-3450 3400);
PAINT GREEN (-3450 3400);
DISPLAY INVISIBLE (-3450 3400);
FORCEPROP 1 LAST HDL_TAP TRUE
J 0
(-3125 3225);
DISPLAY 0.872340 (-3125 3225);
DISPLAY INVISIBLE (-3125 3225);
FORCEPROP 1 LAST PATH I220
J 0
(-3452 3350);
DISPLAY 0.872340 (-3452 3350);
PAINT GREEN (-3452 3350);
DISPLAY INVISIBLE (-3452 3350);
FORCEADD TAP..1
(-3450 3450);
FORCEPROP 3 LASTPIN (-3500 3450) SIG_NAME M_B_CPU1_SB_DQS_DP<9>
J 0
(-3490 3460);
DISPLAY 0.659574 (-3490 3460);
PAINT MONO (-3490 3460);
DISPLAY INVISIBLE (-3490 3460);
FORCEPROP 1 LASTPIN (-3500 3450) BN 9
J 0
(-3512 3458);
DISPLAY 0.489362 (-3512 3458);
PAINT GREEN (-3512 3458);
FORCEPROP 2 LAST CDS_LIB mstr_standard
J 0
(-3450 3450);
DISPLAY 0.723404 (-3450 3450);
PAINT MONO (-3450 3450);
DISPLAY INVISIBLE (-3450 3450);
FORCEPROP 1 LAST BODY_TYPE PLUMBING
J 0
(-3450 3500);
DISPLAY 0.872340 (-3450 3500);
PAINT GREEN (-3450 3500);
DISPLAY INVISIBLE (-3450 3500);
FORCEPROP 1 LAST HDL_TAP TRUE
J 0
(-3125 3325);
DISPLAY 0.872340 (-3125 3325);
DISPLAY INVISIBLE (-3125 3325);
FORCEPROP 1 LAST PATH I221
J 0
(-3452 3450);
DISPLAY 0.872340 (-3452 3450);
PAINT GREEN (-3452 3450);
DISPLAY INVISIBLE (-3452 3450);
FORCEADD TAP..1
(-3450 3250);
FORCEPROP 3 LASTPIN (-3500 3250) SIG_NAME M_B_CPU1_SB_DQS_DP<7>
J 0
(-3490 3260);
DISPLAY 0.659574 (-3490 3260);
PAINT MONO (-3490 3260);
DISPLAY INVISIBLE (-3490 3260);
FORCEPROP 1 LASTPIN (-3500 3250) BN 7
J 0
(-3512 3258);
DISPLAY 0.489362 (-3512 3258);
PAINT GREEN (-3512 3258);
FORCEPROP 2 LAST CDS_LIB mstr_standard
J 0
(-3450 3250);
DISPLAY 0.723404 (-3450 3250);
PAINT MONO (-3450 3250);
DISPLAY INVISIBLE (-3450 3250);
FORCEPROP 1 LAST BODY_TYPE PLUMBING
J 0
(-3450 3300);
DISPLAY 0.872340 (-3450 3300);
PAINT GREEN (-3450 3300);
DISPLAY INVISIBLE (-3450 3300);
FORCEPROP 1 LAST HDL_TAP TRUE
J 0
(-3125 3125);
DISPLAY 0.872340 (-3125 3125);
DISPLAY INVISIBLE (-3125 3125);
FORCEPROP 1 LAST PATH I222
J 0
(-3452 3250);
DISPLAY 0.872340 (-3452 3250);
PAINT GREEN (-3452 3250);
DISPLAY INVISIBLE (-3452 3250);
FORCEADD TAP..1
(-3450 3150);
FORCEPROP 3 LASTPIN (-3500 3150) SIG_NAME M_B_CPU1_SB_DQS_DP<6>
J 0
(-3490 3160);
DISPLAY 0.659574 (-3490 3160);
PAINT MONO (-3490 3160);
DISPLAY INVISIBLE (-3490 3160);
FORCEPROP 1 LASTPIN (-3500 3150) BN 6
J 0
(-3512 3158);
DISPLAY 0.489362 (-3512 3158);
PAINT GREEN (-3512 3158);
FORCEPROP 2 LAST CDS_LIB mstr_standard
J 0
(-3450 3150);
DISPLAY 0.723404 (-3450 3150);
PAINT MONO (-3450 3150);
DISPLAY INVISIBLE (-3450 3150);
FORCEPROP 1 LAST BODY_TYPE PLUMBING
J 0
(-3450 3200);
DISPLAY 0.872340 (-3450 3200);
PAINT GREEN (-3450 3200);
DISPLAY INVISIBLE (-3450 3200);
FORCEPROP 1 LAST HDL_TAP TRUE
J 0
(-3125 3025);
DISPLAY 0.872340 (-3125 3025);
DISPLAY INVISIBLE (-3125 3025);
FORCEPROP 1 LAST PATH I223
J 0
(-3452 3150);
DISPLAY 0.872340 (-3452 3150);
PAINT GREEN (-3452 3150);
DISPLAY INVISIBLE (-3452 3150);
FORCEADD TAP..1
(-3450 3050);
FORCEPROP 3 LASTPIN (-3500 3050) SIG_NAME M_B_CPU1_SB_DQS_DP<5>
J 0
(-3490 3060);
DISPLAY 0.659574 (-3490 3060);
PAINT MONO (-3490 3060);
DISPLAY INVISIBLE (-3490 3060);
FORCEPROP 1 LASTPIN (-3500 3050) BN 5
J 0
(-3512 3058);
DISPLAY 0.489362 (-3512 3058);
PAINT GREEN (-3512 3058);
FORCEPROP 2 LAST CDS_LIB mstr_standard
J 0
(-3450 3050);
DISPLAY 0.723404 (-3450 3050);
PAINT MONO (-3450 3050);
DISPLAY INVISIBLE (-3450 3050);
FORCEPROP 1 LAST BODY_TYPE PLUMBING
J 0
(-3450 3100);
DISPLAY 0.872340 (-3450 3100);
PAINT GREEN (-3450 3100);
DISPLAY INVISIBLE (-3450 3100);
FORCEPROP 1 LAST HDL_TAP TRUE
J 0
(-3125 2925);
DISPLAY 0.872340 (-3125 2925);
DISPLAY INVISIBLE (-3125 2925);
FORCEPROP 1 LAST PATH I224
J 0
(-3452 3050);
DISPLAY 0.872340 (-3452 3050);
PAINT GREEN (-3452 3050);
DISPLAY INVISIBLE (-3452 3050);
FORCEADD TAP..1
(-3250 3000);
FORCEPROP 3 LASTPIN (-3300 3000) SIG_NAME M_B_CPU1_SB_DQS_DN<5>
J 0
(-3290 3010);
DISPLAY 0.659574 (-3290 3010);
PAINT MONO (-3290 3010);
DISPLAY INVISIBLE (-3290 3010);
FORCEPROP 1 LASTPIN (-3300 3000) BN 5
J 0
(-3312 3008);
DISPLAY 0.489362 (-3312 3008);
PAINT GREEN (-3312 3008);
FORCEPROP 2 LAST CDS_LIB mstr_standard
J 0
(-3250 3000);
DISPLAY 0.723404 (-3250 3000);
PAINT MONO (-3250 3000);
DISPLAY INVISIBLE (-3250 3000);
FORCEPROP 1 LAST BODY_TYPE PLUMBING
J 0
(-3250 3050);
DISPLAY 0.872340 (-3250 3050);
PAINT GREEN (-3250 3050);
DISPLAY INVISIBLE (-3250 3050);
FORCEPROP 1 LAST HDL_TAP TRUE
J 0
(-2925 2875);
DISPLAY 0.872340 (-2925 2875);
DISPLAY INVISIBLE (-2925 2875);
FORCEPROP 1 LAST PATH I225
J 0
(-3252 3000);
DISPLAY 0.872340 (-3252 3000);
PAINT GREEN (-3252 3000);
DISPLAY INVISIBLE (-3252 3000);
FORCEADD TAP..1
(-3250 2900);
FORCEPROP 3 LASTPIN (-3300 2900) SIG_NAME M_B_CPU1_SB_DQS_DN<4>
J 0
(-3290 2910);
DISPLAY 0.659574 (-3290 2910);
PAINT MONO (-3290 2910);
DISPLAY INVISIBLE (-3290 2910);
FORCEPROP 1 LASTPIN (-3300 2900) BN 4
J 0
(-3312 2908);
DISPLAY 0.489362 (-3312 2908);
PAINT GREEN (-3312 2908);
FORCEPROP 2 LAST CDS_LIB mstr_standard
J 0
(-3250 2900);
DISPLAY 0.723404 (-3250 2900);
PAINT MONO (-3250 2900);
DISPLAY INVISIBLE (-3250 2900);
FORCEPROP 1 LAST BODY_TYPE PLUMBING
J 0
(-3250 2950);
DISPLAY 0.872340 (-3250 2950);
PAINT GREEN (-3250 2950);
DISPLAY INVISIBLE (-3250 2950);
FORCEPROP 1 LAST HDL_TAP TRUE
J 0
(-2925 2775);
DISPLAY 0.872340 (-2925 2775);
DISPLAY INVISIBLE (-2925 2775);
FORCEPROP 1 LAST PATH I226
J 0
(-3252 2900);
DISPLAY 0.872340 (-3252 2900);
PAINT GREEN (-3252 2900);
DISPLAY INVISIBLE (-3252 2900);
FORCEADD TAP..1
(-3250 2800);
FORCEPROP 3 LASTPIN (-3300 2800) SIG_NAME M_B_CPU1_SB_DQS_DN<3>
J 0
(-3290 2810);
DISPLAY 0.659574 (-3290 2810);
PAINT MONO (-3290 2810);
DISPLAY INVISIBLE (-3290 2810);
FORCEPROP 1 LASTPIN (-3300 2800) BN 3
J 0
(-3312 2808);
DISPLAY 0.489362 (-3312 2808);
PAINT GREEN (-3312 2808);
FORCEPROP 2 LAST CDS_LIB mstr_standard
J 0
(-3250 2800);
DISPLAY 0.723404 (-3250 2800);
PAINT MONO (-3250 2800);
DISPLAY INVISIBLE (-3250 2800);
FORCEPROP 1 LAST BODY_TYPE PLUMBING
J 0
(-3250 2850);
DISPLAY 0.872340 (-3250 2850);
PAINT GREEN (-3250 2850);
DISPLAY INVISIBLE (-3250 2850);
FORCEPROP 1 LAST HDL_TAP TRUE
J 0
(-2925 2675);
DISPLAY 0.872340 (-2925 2675);
DISPLAY INVISIBLE (-2925 2675);
FORCEPROP 1 LAST PATH I227
J 0
(-3252 2800);
DISPLAY 0.872340 (-3252 2800);
PAINT GREEN (-3252 2800);
DISPLAY INVISIBLE (-3252 2800);
FORCEADD TAP..1
(-3250 2700);
FORCEPROP 3 LASTPIN (-3300 2700) SIG_NAME M_B_CPU1_SB_DQS_DN<2>
J 0
(-3290 2710);
DISPLAY 0.659574 (-3290 2710);
PAINT MONO (-3290 2710);
DISPLAY INVISIBLE (-3290 2710);
FORCEPROP 1 LASTPIN (-3300 2700) BN 2
J 0
(-3312 2708);
DISPLAY 0.489362 (-3312 2708);
PAINT GREEN (-3312 2708);
FORCEPROP 2 LAST CDS_LIB mstr_standard
J 0
(-3250 2700);
DISPLAY 0.723404 (-3250 2700);
PAINT MONO (-3250 2700);
DISPLAY INVISIBLE (-3250 2700);
FORCEPROP 1 LAST BODY_TYPE PLUMBING
J 0
(-3250 2750);
DISPLAY 0.872340 (-3250 2750);
PAINT GREEN (-3250 2750);
DISPLAY INVISIBLE (-3250 2750);
FORCEPROP 1 LAST HDL_TAP TRUE
J 0
(-2925 2575);
DISPLAY 0.872340 (-2925 2575);
DISPLAY INVISIBLE (-2925 2575);
FORCEPROP 1 LAST PATH I228
J 0
(-3252 2700);
DISPLAY 0.872340 (-3252 2700);
PAINT GREEN (-3252 2700);
DISPLAY INVISIBLE (-3252 2700);
FORCEADD TAP..1
(-3250 2600);
FORCEPROP 3 LASTPIN (-3300 2600) SIG_NAME M_B_CPU1_SB_DQS_DN<1>
J 0
(-3290 2610);
DISPLAY 0.659574 (-3290 2610);
PAINT MONO (-3290 2610);
DISPLAY INVISIBLE (-3290 2610);
FORCEPROP 1 LASTPIN (-3300 2600) BN 1
J 0
(-3312 2608);
DISPLAY 0.489362 (-3312 2608);
PAINT GREEN (-3312 2608);
FORCEPROP 2 LAST CDS_LIB mstr_standard
J 0
(-3250 2600);
DISPLAY 0.723404 (-3250 2600);
PAINT MONO (-3250 2600);
DISPLAY INVISIBLE (-3250 2600);
FORCEPROP 1 LAST BODY_TYPE PLUMBING
J 0
(-3250 2650);
DISPLAY 0.872340 (-3250 2650);
PAINT GREEN (-3250 2650);
DISPLAY INVISIBLE (-3250 2650);
FORCEPROP 1 LAST HDL_TAP TRUE
J 0
(-2925 2475);
DISPLAY 0.872340 (-2925 2475);
DISPLAY INVISIBLE (-2925 2475);
FORCEPROP 1 LAST PATH I229
J 0
(-3252 2600);
DISPLAY 0.872340 (-3252 2600);
PAINT GREEN (-3252 2600);
DISPLAY INVISIBLE (-3252 2600);
FORCEADD TAP..1
R 2
(-7775 3325);
FORCEPROP 3 LASTPIN (-7725 3325) SIG_NAME M_B_CPU1_SB_CB<0>
J 0
(-7715 3335);
DISPLAY 0.659574 (-7715 3335);
PAINT MONO (-7715 3335);
DISPLAY INVISIBLE (-7715 3335);
FORCEPROP 1 LASTPIN (-7725 3325) BN 0
J 2
(-7713 3333);
DISPLAY 0.489362 (-7713 3333);
PAINT GREEN (-7713 3333);
FORCEPROP 2 LAST CDS_LIB mstr_standard
J 0
(-7775 3325);
DISPLAY 0.723404 (-7775 3325);
PAINT MONO (-7775 3325);
DISPLAY INVISIBLE (-7775 3325);
FORCEPROP 1 LAST BODY_TYPE PLUMBING
J 2
(-7775 3375);
DISPLAY 0.872340 (-7775 3375);
PAINT GREEN (-7775 3375);
DISPLAY INVISIBLE (-7775 3375);
FORCEPROP 1 LAST HDL_TAP TRUE
J 2
(-8100 3200);
DISPLAY 0.872340 (-8100 3200);
DISPLAY INVISIBLE (-8100 3200);
FORCEPROP 1 LAST PATH I23
J 2
(-7773 3325);
DISPLAY 0.872340 (-7773 3325);
PAINT GREEN (-7773 3325);
DISPLAY INVISIBLE (-7773 3325);
FORCEADD TAP..1
(-3250 2500);
FORCEPROP 3 LASTPIN (-3300 2500) SIG_NAME M_B_CPU1_SB_DQS_DN<0>
J 0
(-3290 2510);
DISPLAY 0.659574 (-3290 2510);
PAINT MONO (-3290 2510);
DISPLAY INVISIBLE (-3290 2510);
FORCEPROP 1 LASTPIN (-3300 2500) BN 0
J 0
(-3312 2508);
DISPLAY 0.489362 (-3312 2508);
PAINT GREEN (-3312 2508);
FORCEPROP 2 LAST CDS_LIB mstr_standard
J 0
(-3250 2500);
DISPLAY 0.723404 (-3250 2500);
PAINT MONO (-3250 2500);
DISPLAY INVISIBLE (-3250 2500);
FORCEPROP 1 LAST BODY_TYPE PLUMBING
J 0
(-3250 2550);
DISPLAY 0.872340 (-3250 2550);
PAINT GREEN (-3250 2550);
DISPLAY INVISIBLE (-3250 2550);
FORCEPROP 1 LAST HDL_TAP TRUE
J 0
(-2925 2375);
DISPLAY 0.872340 (-2925 2375);
DISPLAY INVISIBLE (-2925 2375);
FORCEPROP 1 LAST PATH I230
J 0
(-3252 2500);
DISPLAY 0.872340 (-3252 2500);
PAINT GREEN (-3252 2500);
DISPLAY INVISIBLE (-3252 2500);
FORCEADD TAP..1
(-3450 2850);
FORCEPROP 3 LASTPIN (-3500 2850) SIG_NAME M_B_CPU1_SB_DQS_DP<3>
J 0
(-3490 2860);
DISPLAY 0.659574 (-3490 2860);
PAINT MONO (-3490 2860);
DISPLAY INVISIBLE (-3490 2860);
FORCEPROP 1 LASTPIN (-3500 2850) BN 3
J 0
(-3512 2858);
DISPLAY 0.489362 (-3512 2858);
PAINT GREEN (-3512 2858);
FORCEPROP 2 LAST CDS_LIB mstr_standard
J 0
(-3450 2850);
DISPLAY 0.723404 (-3450 2850);
PAINT MONO (-3450 2850);
DISPLAY INVISIBLE (-3450 2850);
FORCEPROP 1 LAST BODY_TYPE PLUMBING
J 0
(-3450 2900);
DISPLAY 0.872340 (-3450 2900);
PAINT GREEN (-3450 2900);
DISPLAY INVISIBLE (-3450 2900);
FORCEPROP 1 LAST HDL_TAP TRUE
J 0
(-3125 2725);
DISPLAY 0.872340 (-3125 2725);
DISPLAY INVISIBLE (-3125 2725);
FORCEPROP 1 LAST PATH I231
J 0
(-3452 2850);
DISPLAY 0.872340 (-3452 2850);
PAINT GREEN (-3452 2850);
DISPLAY INVISIBLE (-3452 2850);
FORCEADD TAP..1
(-3450 2950);
FORCEPROP 3 LASTPIN (-3500 2950) SIG_NAME M_B_CPU1_SB_DQS_DP<4>
J 0
(-3490 2960);
DISPLAY 0.659574 (-3490 2960);
PAINT MONO (-3490 2960);
DISPLAY INVISIBLE (-3490 2960);
FORCEPROP 1 LASTPIN (-3500 2950) BN 4
J 0
(-3512 2958);
DISPLAY 0.489362 (-3512 2958);
PAINT GREEN (-3512 2958);
FORCEPROP 2 LAST CDS_LIB mstr_standard
J 0
(-3450 2950);
DISPLAY 0.723404 (-3450 2950);
PAINT MONO (-3450 2950);
DISPLAY INVISIBLE (-3450 2950);
FORCEPROP 1 LAST BODY_TYPE PLUMBING
J 0
(-3450 3000);
DISPLAY 0.872340 (-3450 3000);
PAINT GREEN (-3450 3000);
DISPLAY INVISIBLE (-3450 3000);
FORCEPROP 1 LAST HDL_TAP TRUE
J 0
(-3125 2825);
DISPLAY 0.872340 (-3125 2825);
DISPLAY INVISIBLE (-3125 2825);
FORCEPROP 1 LAST PATH I232
J 0
(-3452 2950);
DISPLAY 0.872340 (-3452 2950);
PAINT GREEN (-3452 2950);
DISPLAY INVISIBLE (-3452 2950);
FORCEADD TAP..1
(-3450 2750);
FORCEPROP 3 LASTPIN (-3500 2750) SIG_NAME M_B_CPU1_SB_DQS_DP<2>
J 0
(-3490 2760);
DISPLAY 0.659574 (-3490 2760);
PAINT MONO (-3490 2760);
DISPLAY INVISIBLE (-3490 2760);
FORCEPROP 1 LASTPIN (-3500 2750) BN 2
J 0
(-3512 2758);
DISPLAY 0.489362 (-3512 2758);
PAINT GREEN (-3512 2758);
FORCEPROP 2 LAST CDS_LIB mstr_standard
J 0
(-3450 2750);
DISPLAY 0.723404 (-3450 2750);
PAINT MONO (-3450 2750);
DISPLAY INVISIBLE (-3450 2750);
FORCEPROP 1 LAST BODY_TYPE PLUMBING
J 0
(-3450 2800);
DISPLAY 0.872340 (-3450 2800);
PAINT GREEN (-3450 2800);
DISPLAY INVISIBLE (-3450 2800);
FORCEPROP 1 LAST HDL_TAP TRUE
J 0
(-3125 2625);
DISPLAY 0.872340 (-3125 2625);
DISPLAY INVISIBLE (-3125 2625);
FORCEPROP 1 LAST PATH I233
J 0
(-3452 2750);
DISPLAY 0.872340 (-3452 2750);
PAINT GREEN (-3452 2750);
DISPLAY INVISIBLE (-3452 2750);
FORCEADD TAP..1
(-3450 2550);
FORCEPROP 3 LASTPIN (-3500 2550) SIG_NAME M_B_CPU1_SB_DQS_DP<0>
J 0
(-3490 2560);
DISPLAY 0.659574 (-3490 2560);
PAINT MONO (-3490 2560);
DISPLAY INVISIBLE (-3490 2560);
FORCEPROP 1 LASTPIN (-3500 2550) BN 0
J 0
(-3512 2558);
DISPLAY 0.489362 (-3512 2558);
PAINT GREEN (-3512 2558);
FORCEPROP 2 LAST CDS_LIB mstr_standard
J 0
(-3450 2550);
DISPLAY 0.723404 (-3450 2550);
PAINT MONO (-3450 2550);
DISPLAY INVISIBLE (-3450 2550);
FORCEPROP 1 LAST BODY_TYPE PLUMBING
J 0
(-3450 2600);
DISPLAY 0.872340 (-3450 2600);
PAINT GREEN (-3450 2600);
DISPLAY INVISIBLE (-3450 2600);
FORCEPROP 1 LAST HDL_TAP TRUE
J 0
(-3125 2425);
DISPLAY 0.872340 (-3125 2425);
DISPLAY INVISIBLE (-3125 2425);
FORCEPROP 1 LAST PATH I234
J 0
(-3452 2550);
DISPLAY 0.872340 (-3452 2550);
PAINT GREEN (-3452 2550);
DISPLAY INVISIBLE (-3452 2550);
FORCEADD TAP..1
(-3450 2650);
FORCEPROP 3 LASTPIN (-3500 2650) SIG_NAME M_B_CPU1_SB_DQS_DP<1>
J 0
(-3490 2660);
DISPLAY 0.659574 (-3490 2660);
PAINT MONO (-3490 2660);
DISPLAY INVISIBLE (-3490 2660);
FORCEPROP 1 LASTPIN (-3500 2650) BN 1
J 0
(-3512 2658);
DISPLAY 0.489362 (-3512 2658);
PAINT GREEN (-3512 2658);
FORCEPROP 2 LAST CDS_LIB mstr_standard
J 0
(-3450 2650);
DISPLAY 0.723404 (-3450 2650);
PAINT MONO (-3450 2650);
DISPLAY INVISIBLE (-3450 2650);
FORCEPROP 1 LAST BODY_TYPE PLUMBING
J 0
(-3450 2700);
DISPLAY 0.872340 (-3450 2700);
PAINT GREEN (-3450 2700);
DISPLAY INVISIBLE (-3450 2700);
FORCEPROP 1 LAST HDL_TAP TRUE
J 0
(-3125 2525);
DISPLAY 0.872340 (-3125 2525);
DISPLAY INVISIBLE (-3125 2525);
FORCEPROP 1 LAST PATH I235
J 0
(-3452 2650);
DISPLAY 0.872340 (-3452 2650);
PAINT GREEN (-3452 2650);
DISPLAY INVISIBLE (-3452 2650);
FORCEADD SCONN288_DDR506112002KQ..2
(-4400 3500);
FORCEPROP 1 LAST LOCATION J26
J 0
(-5000 4825);
DISPLAY 0.468085 (-5000 4825);
PAINT SKYBLUE (-5000 4825);
FORCEPROP 0 LAST $SEC 2
J 0
(-4850 4975);
DISPLAY 0.680851 (-4850 4975);
PAINT MONO (-4850 4975);
DISPLAY INVISIBLE (-4850 4975);
FORCEPROP 0 LAST CDS_SEC 2
J 0
(-4850 4975);
DISPLAY 1.021277 (-4850 4975);
DISPLAY INVISIBLE (-4850 4975);
FORCEPROP 0 LASTPIN (-3650 3550) $PN 12
J 0
(-3640 3560);
DISPLAY 0.680851 (-3640 3560);
PAINT MONO (-3640 3560);
FORCEPROP 0 LASTPIN (-3650 3600) $PN 11
J 0
(-3640 3610);
DISPLAY 0.680851 (-3640 3610);
PAINT MONO (-3640 3610);
FORCEPROP 0 LASTPIN (-3650 2500) $PN 105
J 0
(-3640 2510);
DISPLAY 0.680851 (-3640 2510);
PAINT MONO (-3640 2510);
FORCEPROP 0 LASTPIN (-3650 2550) $PN 104
J 0
(-3640 2560);
DISPLAY 0.680851 (-3640 2560);
PAINT MONO (-3640 2560);
FORCEPROP 0 LASTPIN (-3650 3650) $PN 23
J 0
(-3640 3660);
DISPLAY 0.680851 (-3640 3660);
PAINT MONO (-3640 3660);
FORCEPROP 0 LASTPIN (-3650 3700) $PN 22
J 0
(-3640 3710);
DISPLAY 0.680851 (-3640 3710);
PAINT MONO (-3640 3710);
FORCEPROP 0 LASTPIN (-3650 2600) $PN 116
J 0
(-3640 2610);
DISPLAY 0.680851 (-3640 2610);
PAINT MONO (-3640 2610);
FORCEPROP 0 LASTPIN (-3650 2650) $PN 115
J 0
(-3640 2660);
DISPLAY 0.680851 (-3640 2660);
PAINT MONO (-3640 2660);
FORCEPROP 0 LASTPIN (-3650 3750) $PN 34
J 0
(-3640 3760);
DISPLAY 0.680851 (-3640 3760);
PAINT MONO (-3640 3760);
FORCEPROP 0 LASTPIN (-3650 3800) $PN 33
J 0
(-3640 3810);
DISPLAY 0.680851 (-3640 3810);
PAINT MONO (-3640 3810);
FORCEPROP 0 LASTPIN (-3650 2700) $PN 127
J 0
(-3640 2710);
DISPLAY 0.680851 (-3640 2710);
PAINT MONO (-3640 2710);
FORCEPROP 0 LASTPIN (-3650 2750) $PN 126
J 0
(-3640 2760);
DISPLAY 0.680851 (-3640 2760);
PAINT MONO (-3640 2760);
FORCEPROP 0 LASTPIN (-3650 3850) $PN 45
J 0
(-3640 3860);
DISPLAY 0.680851 (-3640 3860);
PAINT MONO (-3640 3860);
FORCEPROP 0 LASTPIN (-3650 3900) $PN 44
J 0
(-3640 3910);
DISPLAY 0.680851 (-3640 3910);
PAINT MONO (-3640 3910);
FORCEPROP 0 LASTPIN (-3650 2800) $PN 138
J 0
(-3640 2810);
DISPLAY 0.680851 (-3640 2810);
PAINT MONO (-3640 2810);
FORCEPROP 0 LASTPIN (-3650 2850) $PN 137
J 0
(-3640 2860);
DISPLAY 0.680851 (-3640 2860);
PAINT MONO (-3640 2860);
FORCEPROP 0 LASTPIN (-3650 3950) $PN 56
J 0
(-3640 3960);
DISPLAY 0.680851 (-3640 3960);
PAINT MONO (-3640 3960);
FORCEPROP 0 LASTPIN (-3650 4000) $PN 55
J 0
(-3640 4010);
DISPLAY 0.680851 (-3640 4010);
PAINT MONO (-3640 4010);
FORCEPROP 0 LASTPIN (-3650 2900) $PN 238
J 0
(-3640 2910);
DISPLAY 0.680851 (-3640 2910);
PAINT MONO (-3640 2910);
FORCEPROP 0 LASTPIN (-3650 2950) $PN 239
J 0
(-3640 2960);
DISPLAY 0.680851 (-3640 2960);
PAINT MONO (-3640 2960);
FORCEPROP 0 LASTPIN (-3650 4050) $PN 156
J 0
(-3640 4060);
DISPLAY 0.680851 (-3640 4060);
PAINT MONO (-3640 4060);
FORCEPROP 0 LASTPIN (-3650 4100) $PN 157
J 0
(-3640 4110);
DISPLAY 0.680851 (-3640 4110);
PAINT MONO (-3640 4110);
FORCEPROP 0 LASTPIN (-3650 3000) $PN 249
J 0
(-3640 3010);
DISPLAY 0.680851 (-3640 3010);
PAINT MONO (-3640 3010);
FORCEPROP 0 LASTPIN (-3650 3050) $PN 250
J 0
(-3640 3060);
DISPLAY 0.680851 (-3640 3060);
PAINT MONO (-3640 3060);
FORCEPROP 0 LASTPIN (-3650 4150) $PN 167
J 0
(-3640 4160);
DISPLAY 0.680851 (-3640 4160);
PAINT MONO (-3640 4160);
FORCEPROP 0 LASTPIN (-3650 4200) $PN 168
J 0
(-3640 4210);
DISPLAY 0.680851 (-3640 4210);
PAINT MONO (-3640 4210);
FORCEPROP 0 LASTPIN (-3650 3100) $PN 260
J 0
(-3640 3110);
DISPLAY 0.680851 (-3640 3110);
PAINT MONO (-3640 3110);
FORCEPROP 0 LASTPIN (-3650 3150) $PN 261
J 0
(-3640 3160);
DISPLAY 0.680851 (-3640 3160);
PAINT MONO (-3640 3160);
FORCEPROP 0 LASTPIN (-3650 4250) $PN 178
J 0
(-3640 4260);
DISPLAY 0.680851 (-3640 4260);
PAINT MONO (-3640 4260);
FORCEPROP 0 LASTPIN (-3650 4300) $PN 179
J 0
(-3640 4310);
DISPLAY 0.680851 (-3640 4310);
PAINT MONO (-3640 4310);
FORCEPROP 0 LASTPIN (-3650 3200) $PN 271
J 0
(-3640 3210);
DISPLAY 0.680851 (-3640 3210);
PAINT MONO (-3640 3210);
FORCEPROP 0 LASTPIN (-3650 3250) $PN 272
J 0
(-3640 3260);
DISPLAY 0.680851 (-3640 3260);
PAINT MONO (-3640 3260);
FORCEPROP 0 LASTPIN (-3650 4350) $PN 189
J 0
(-3640 4360);
DISPLAY 0.680851 (-3640 4360);
PAINT MONO (-3640 4360);
FORCEPROP 0 LASTPIN (-3650 4400) $PN 190
J 0
(-3640 4410);
DISPLAY 0.680851 (-3640 4410);
PAINT MONO (-3640 4410);
FORCEPROP 0 LASTPIN (-3650 3300) $PN 282
J 0
(-3640 3310);
DISPLAY 0.680851 (-3640 3310);
PAINT MONO (-3640 3310);
FORCEPROP 0 LASTPIN (-3650 3350) $PN 283
J 0
(-3640 3360);
DISPLAY 0.680851 (-3640 3360);
PAINT MONO (-3640 3360);
FORCEPROP 0 LASTPIN (-3650 4450) $PN 200
J 0
(-3640 4460);
DISPLAY 0.680851 (-3640 4460);
PAINT MONO (-3640 4460);
FORCEPROP 0 LASTPIN (-3650 4500) $PN 201
J 0
(-3640 4510);
DISPLAY 0.680851 (-3640 4510);
PAINT MONO (-3640 4510);
FORCEPROP 0 LASTPIN (-3650 3400) $PN 94
J 0
(-3640 3410);
DISPLAY 0.680851 (-3640 3410);
PAINT MONO (-3640 3410);
FORCEPROP 0 LASTPIN (-3650 3450) $PN 93
J 0
(-3640 3460);
DISPLAY 0.680851 (-3640 3460);
PAINT MONO (-3640 3460);
FORCEPROP 2 LAST VALUE SCONN288_DDR506112002KQ
J 0
(-4850 4875);
DISPLAY 0.489362 (-4850 4875);
PAINT SKYBLUE (-4850 4875);
FORCEPROP 2 LAST PART_TYPE SMLF
J 0
(-4850 4925);
DISPLAY 1.021277 (-4850 4925);
FORCEPROP 1 LAST MATERIAL IO
J 0
(-5000 4675);
DISPLAY 0.468085 (-5000 4675);
PAINT SKYBLUE (-5000 4675);
FORCEPROP 1 LAST CDS_LMAN_SYM_OUTLINE -600,1150,600,-1150
J 0
(-4400 3500);
DISPLAY 0.468085 (-4400 3500);
PAINT GREEN (-4400 3500);
DISPLAY INVISIBLE (-4400 3500);
FORCEPROP 1 LAST NEEDS_NO_SIZE TRUE
J 0
(-4400 3500);
DISPLAY 0.723404 (-4400 3500);
PAINT GREEN (-4400 3500);
DISPLAY INVISIBLE (-4400 3500);
FORCEPROP 2 LAST CDS_LIB pure_quanta
J 0
(-4400 3500);
DISPLAY INVISIBLE (-4400 3500);
FORCEPROP 1 LAST PATH I236
J 0
(-4400 3500);
DISPLAY 0.723404 (-4400 3500);
PAINT GREEN (-4400 3500);
DISPLAY INVISIBLE (-4400 3500);
FORCEPROP 1 LAST PART_NUMBER DFHST8FS479
J 0
(-5000 4750);
DISPLAY 0.468085 (-5000 4750);
PAINT SKYBLUE (-5000 4750);
DISPLAY INVISIBLE (-5000 4750);
FORCEADD GND..1
(-2875 5175);
FORCEPROP 3 LASTPIN (-2875 5225) SIG_NAME GND\g
J 0
(-2865 5235);
DISPLAY 0.659574 (-2865 5235);
PAINT MONO (-2865 5235);
DISPLAY INVISIBLE (-2865 5235);
FORCEPROP 2 LAST CDS_LIB pure_quanta_power
J 0
(-2875 5175);
DISPLAY INVISIBLE (-2875 5175);
FORCEPROP 2 LAST BOM_COST MEM
J 0
(-2850 5300);
DISPLAY 0.659574 (-2850 5300);
DISPLAY INVISIBLE (-2850 5300);
FORCEPROP 1 LAST SIZE 1B
J 0
(-2800 5125);
DISPLAY 0.723404 (-2800 5125);
PAINT GREEN (-2800 5125);
DISPLAY INVISIBLE (-2800 5125);
FORCEPROP 2 LAST ROOM MEM_EFGH_DECOUPLING_CAPS
J 0
(-2850 5250);
DISPLAY 0.659574 (-2850 5250);
PAINT RED (-2850 5250);
DISPLAY INVISIBLE (-2850 5250);
FORCEPROP 1 LAST HDL_POWER GND
J 0
(-2875 5325);
DISPLAY 0.723404 (-2875 5325);
PAINT GREEN (-2875 5325);
DISPLAY INVISIBLE (-2875 5325);
FORCEPROP 1 LAST PATH I237
J 0
(-2800 5175);
DISPLAY 0.872340 (-2800 5175);
PAINT AQUA (-2800 5175);
DISPLAY INVISIBLE (-2800 5175);
FORCEADD Q_CAP..1
R 2
(-2875 5525);
FORCEPROP 1 LAST LOCATION C175
J 2
(-2925 5625);
DISPLAY 0.489362 (-2925 5625);
PAINT SKYBLUE (-2925 5625);
FORCEPROP 0 LAST $SEC 1
J 0
(-2925 5675);
DISPLAY 0.680851 (-2925 5675);
PAINT MONO (-2925 5675);
DISPLAY INVISIBLE (-2925 5675);
FORCEPROP 0 LAST CDS_SEC 1
J 0
(-2925 5675);
DISPLAY 0.680851 (-2925 5675);
DISPLAY INVISIBLE (-2925 5675);
FORCEPROP 1 LASTPIN (-2875 5625) $PN 1
J 2
(-2885 5605);
DISPLAY 0.489362 (-2885 5605);
PAINT MONO (-2885 5605);
FORCEPROP 1 LASTPIN (-2875 5425) $PN 2
J 2
(-2885 5405);
DISPLAY 0.489362 (-2885 5405);
PAINT MONO (-2885 5405);
FORCEPROP 1 LAST PACK_TYPE C0805
J 2
(-2925 5325);
DISPLAY 0.489362 (-2925 5325);
PAINT SKYBLUE (-2925 5325);
FORCEPROP 1 LAST TOLERANCE 10%
J 2
(-2925 5475);
DISPLAY 0.489362 (-2925 5475);
PAINT SKYBLUE (-2925 5475);
FORCEPROP 1 LAST MATERIAL X6S
J 2
(-2925 5425);
DISPLAY 0.489362 (-2925 5425);
PAINT SKYBLUE (-2925 5425);
FORCEPROP 1 LAST VALUE 10UF
J 2
(-2925 5575);
DISPLAY 0.489362 (-2925 5575);
PAINT SKYBLUE (-2925 5575);
FORCEPROP 1 LAST VOLTAGE 25V
J 2
(-2925 5525);
DISPLAY 0.489362 (-2925 5525);
PAINT SKYBLUE (-2925 5525);
FORCEPROP 2 LAST CDS_LIB pure_quanta
J 0
(-2875 5525);
DISPLAY INVISIBLE (-2875 5525);
FORCEPROP 0 LAST BOM_COST MEM
J 2
(-2930 5670);
DISPLAY 0.595745 (-2930 5670);
PAINT MONO (-2930 5670);
DISPLAY INVISIBLE (-2930 5670);
FORCEPROP 2 LAST ROOM 
J 2
(-2930 5670);
DISPLAY 0.595745 (-2930 5670);
PAINT RED (-2930 5670);
DISPLAY INVISIBLE (-2930 5670);
FORCEPROP 1 LAST PATH I238
J 2
(-2925 5675);
DISPLAY 0.978723 (-2925 5675);
PAINT WHITE (-2925 5675);
DISPLAY INVISIBLE (-2925 5675);
FORCEPROP 1 LAST PART_NUMBER CH6104KEA00
J 2
(-2925 5375);
DISPLAY 0.489362 (-2925 5375);
PAINT SKYBLUE (-2925 5375);
DISPLAY INVISIBLE (-2925 5375);
FORCEADD Q_CAP..1
R 2
(-2300 5525);
FORCEPROP 1 LAST LOCATION C177
J 2
(-2350 5625);
DISPLAY 0.489362 (-2350 5625);
PAINT SKYBLUE (-2350 5625);
FORCEPROP 0 LAST $SEC 1
J 0
(-2350 5675);
DISPLAY 0.680851 (-2350 5675);
PAINT MONO (-2350 5675);
DISPLAY INVISIBLE (-2350 5675);
FORCEPROP 0 LAST CDS_SEC 1
J 0
(-2350 5675);
DISPLAY 0.680851 (-2350 5675);
DISPLAY INVISIBLE (-2350 5675);
FORCEPROP 1 LASTPIN (-2300 5625) $PN 1
J 2
(-2310 5605);
DISPLAY 0.489362 (-2310 5605);
PAINT MONO (-2310 5605);
FORCEPROP 1 LASTPIN (-2300 5425) $PN 2
J 2
(-2310 5405);
DISPLAY 0.489362 (-2310 5405);
PAINT MONO (-2310 5405);
FORCEPROP 1 LAST VALUE 10UF
J 2
(-2350 5575);
DISPLAY 0.489362 (-2350 5575);
PAINT SKYBLUE (-2350 5575);
FORCEPROP 1 LAST VOLTAGE 25V
J 2
(-2350 5525);
DISPLAY 0.489362 (-2350 5525);
PAINT SKYBLUE (-2350 5525);
FORCEPROP 1 LAST TOLERANCE 10%
J 2
(-2350 5475);
DISPLAY 0.489362 (-2350 5475);
PAINT SKYBLUE (-2350 5475);
FORCEPROP 1 LAST PACK_TYPE C0805
J 2
(-2350 5325);
DISPLAY 0.489362 (-2350 5325);
PAINT SKYBLUE (-2350 5325);
FORCEPROP 1 LAST MATERIAL X6S
J 2
(-2350 5425);
DISPLAY 0.489362 (-2350 5425);
PAINT SKYBLUE (-2350 5425);
FORCEPROP 2 LAST CDS_LIB pure_quanta
J 0
(-2300 5525);
DISPLAY INVISIBLE (-2300 5525);
FORCEPROP 0 LAST BOM_COST MEM
J 2
(-2355 5670);
DISPLAY 0.595745 (-2355 5670);
PAINT MONO (-2355 5670);
DISPLAY INVISIBLE (-2355 5670);
FORCEPROP 2 LAST ROOM 
J 2
(-2355 5670);
DISPLAY 0.595745 (-2355 5670);
PAINT RED (-2355 5670);
DISPLAY INVISIBLE (-2355 5670);
FORCEPROP 1 LAST PATH I239
J 2
(-2350 5675);
DISPLAY 0.978723 (-2350 5675);
PAINT WHITE (-2350 5675);
DISPLAY INVISIBLE (-2350 5675);
FORCEPROP 1 LAST PART_NUMBER CH6104KEA00
J 2
(-2350 5375);
DISPLAY 0.489362 (-2350 5375);
PAINT SKYBLUE (-2350 5375);
DISPLAY INVISIBLE (-2350 5375);
FORCEADD TAP..1
R 2
(-7775 3375);
FORCEPROP 3 LASTPIN (-7725 3375) SIG_NAME M_B_CPU1_SB_CB<1>
J 0
(-7715 3385);
DISPLAY 0.659574 (-7715 3385);
PAINT MONO (-7715 3385);
DISPLAY INVISIBLE (-7715 3385);
FORCEPROP 1 LASTPIN (-7725 3375) BN 1
J 2
(-7713 3383);
DISPLAY 0.489362 (-7713 3383);
PAINT GREEN (-7713 3383);
FORCEPROP 2 LAST CDS_LIB mstr_standard
J 0
(-7775 3375);
DISPLAY 0.723404 (-7775 3375);
PAINT MONO (-7775 3375);
DISPLAY INVISIBLE (-7775 3375);
FORCEPROP 1 LAST BODY_TYPE PLUMBING
J 2
(-7775 3425);
DISPLAY 0.872340 (-7775 3425);
PAINT GREEN (-7775 3425);
DISPLAY INVISIBLE (-7775 3425);
FORCEPROP 1 LAST HDL_TAP TRUE
J 2
(-8100 3250);
DISPLAY 0.872340 (-8100 3250);
DISPLAY INVISIBLE (-8100 3250);
FORCEPROP 1 LAST PATH I24
J 2
(-7773 3375);
DISPLAY 0.872340 (-7773 3375);
PAINT GREEN (-7773 3375);
DISPLAY INVISIBLE (-7773 3375);
FORCEADD UNIVERSAL_POWER..1
(-2875 5850);
FORCEPROP 3 LASTPIN (-2875 5800) SIG_NAME P12V_MEM_CPU1\g
J 0
(-2865 5810);
DISPLAY 0.659574 (-2865 5810);
PAINT MONO (-2865 5810);
DISPLAY INVISIBLE (-2865 5810);
FORCEPROP 1 LAST HDL_POWER P12V_MEM_CPU1
J 1
(-2875 5900);
DISPLAY 0.489362 (-2875 5900);
PAINT GREEN (-2875 5900);
FORCEPROP 2 LAST CDS_LIB pure_quanta_power
J 0
(-2875 5850);
DISPLAY INVISIBLE (-2875 5850);
FORCEPROP 1 LAST PATH I240
J 0
(-2825 5875);
DISPLAY 0.872340 (-2825 5875);
PAINT AQUA (-2825 5875);
DISPLAY INVISIBLE (-2825 5875);
FORCEADD OFFPAGE..1
(-8475 2750);
FORCEPROP 2 LAST $XR5 103 
J 0
(-9327 2750);
DISPLAY 0.638298 (-9327 2750);
PAINT MONO (-9327 2750);
FORCEPROP 2 LAST $XR4 102 
J 0
(-9207 2750);
DISPLAY 0.638298 (-9207 2750);
PAINT MONO (-9207 2750);
FORCEPROP 2 LAST $XR3 101 
J 0
(-9087 2750);
DISPLAY 0.638298 (-9087 2750);
PAINT MONO (-9087 2750);
FORCEPROP 2 LAST $XR2 100 
J 0
(-8967 2750);
DISPLAY 0.638298 (-8967 2750);
PAINT MONO (-8967 2750);
FORCEPROP 2 LAST $XR1 98 
J 0
(-8847 2750);
DISPLAY 0.638298 (-8847 2750);
PAINT MONO (-8847 2750);
FORCEPROP 2 LAST $XR0 159 
J 0
(-8757 2750);
DISPLAY 0.638298 (-8757 2750);
PAINT MONO (-8757 2750);
FORCEPROP 2 LAST CDS_LIB mstr_standard
J 0
(-8475 2750);
DISPLAY 0.808511 (-8475 2750);
DISPLAY INVISIBLE (-8475 2750);
FORCEPROP 1 LAST OFFPAGE TRUE
J 0
(-8150 2625);
DISPLAY 0.872340 (-8150 2625);
PAINT GREEN (-8150 2625);
DISPLAY INVISIBLE (-8150 2625);
FORCEPROP 1 LAST COMMENT_BODY TRUE
J 0
(-8350 2650);
DISPLAY 0.872340 (-8350 2650);
PAINT GREEN (-8350 2650);
DISPLAY INVISIBLE (-8350 2650);
FORCEPROP 2 LAST PATH I241
J 0
(-8750 2800);
DISPLAY 0.680851 (-8750 2800);
DISPLAY INVISIBLE (-8750 2800);
FORCEADD Q_RES..1
(-7825 2750);
FORCEPROP 1 LAST LOCATION R1581
J 0
(-7875 2775);
DISPLAY 0.510638 (-7875 2775);
PAINT SKYBLUE (-7875 2775);
FORCEPROP 0 LAST $SEC 1
J 0
(-7875 2850);
DISPLAY 0.680851 (-7875 2850);
PAINT MONO (-7875 2850);
DISPLAY INVISIBLE (-7875 2850);
FORCEPROP 0 LAST CDS_SEC 1
J 0
(-7875 2850);
DISPLAY 0.680851 (-7875 2850);
DISPLAY INVISIBLE (-7875 2850);
FORCEPROP 1 LASTPIN (-7925 2750) $PN 1
J 0
(-7913 2762);
DISPLAY 0.787234 (-7913 2762);
PAINT MONO (-7913 2762);
FORCEPROP 1 LASTPIN (-7725 2750) $PN 2
J 0
(-7763 2762);
DISPLAY 0.787234 (-7763 2762);
PAINT MONO (-7763 2762);
FORCEPROP 1 LAST VALUE 49.9
J 2
(-7675 2800);
DISPLAY 0.510638 (-7675 2800);
PAINT SKYBLUE (-7675 2800);
FORCEPROP 2 LAST CDS_LIB pure_quanta
J 0
(-7825 2750);
DISPLAY INVISIBLE (-7825 2750);
FORCEPROP 1 LAST MATERIAL CHIP
J 0
(-7825 2600);
DISPLAY 0.978723 (-7825 2600);
DISPLAY INVISIBLE (-7825 2600);
FORCEPROP 1 LAST PACK_TYPE 0402LF
J 0
(-7575 2600);
DISPLAY 0.978723 (-7575 2600);
DISPLAY INVISIBLE (-7575 2600);
FORCEPROP 1 LAST WATTAGE 1/16W
J 2
(-7850 2600);
DISPLAY 0.978723 (-7850 2600);
DISPLAY INVISIBLE (-7850 2600);
FORCEPROP 1 LAST TOLERANCE 1%
J 0
(-7825 2650);
DISPLAY 0.978723 (-7825 2650);
DISPLAY INVISIBLE (-7825 2650);
FORCEPROP 1 LAST PATH I242
J 0
(-7875 2900);
DISPLAY 0.978723 (-7875 2900);
PAINT WHITE (-7875 2900);
DISPLAY INVISIBLE (-7875 2900);
FORCEPROP 1 LAST PART_NUMBER CS04992FB07
J 0
(-7875 2850);
DISPLAY 0.978723 (-7875 2850);
DISPLAY INVISIBLE (-7875 2850);
FORCEADD Q_RES..1
(-8200 2975);
FORCEPROP 1 LAST LOCATION R1696
J 0
(-8400 2975);
DISPLAY 0.638298 (-8400 2975);
FORCEPROP 0 LAST $SEC 1
J 0
(-8350 3025);
DISPLAY 0.680851 (-8350 3025);
PAINT MONO (-8350 3025);
DISPLAY INVISIBLE (-8350 3025);
FORCEPROP 0 LAST CDS_SEC 1
J 0
(-8350 3025);
DISPLAY 0.680851 (-8350 3025);
DISPLAY INVISIBLE (-8350 3025);
FORCEPROP 1 LASTPIN (-8300 2975) $PN 1
J 0
(-8288 2987);
DISPLAY 0.787234 (-8288 2987);
PAINT MONO (-8288 2987);
FORCEPROP 1 LASTPIN (-8100 2975) $PN 2
J 0
(-8138 2987);
DISPLAY 0.787234 (-8138 2987);
PAINT MONO (-8138 2987);
FORCEPROP 1 LAST PACK_TYPE 0402LF
J 0
(-8150 2950);
DISPLAY 0.404255 (-8150 2950);
FORCEPROP 1 LAST MATERIAL CHIP
J 0
(-8300 2950);
DISPLAY 0.404255 (-8300 2950);
FORCEPROP 1 LAST VALUE 10
J 2
(-8050 2975);
DISPLAY 0.404255 (-8050 2975);
FORCEPROP 1 LAST TOLERANCE 1%
J 0
(-8200 2875);
DISPLAY 0.978723 (-8200 2875);
DISPLAY INVISIBLE (-8200 2875);
FORCEPROP 1 LAST WATTAGE 1/16W
J 2
(-8225 2825);
DISPLAY 0.978723 (-8225 2825);
DISPLAY INVISIBLE (-8225 2825);
FORCEPROP 2 LAST CDS_LIB pure_quanta
J 0
(-8200 2975);
DISPLAY INVISIBLE (-8200 2975);
FORCEPROP 1 LAST PATH I243
J 0
(-8250 3125);
DISPLAY 0.978723 (-8250 3125);
PAINT WHITE (-8250 3125);
DISPLAY INVISIBLE (-8250 3125);
FORCEPROP 1 LAST PART_NUMBER CS01002FB07
J 0
(-8250 3075);
DISPLAY 0.978723 (-8250 3075);
DISPLAY INVISIBLE (-8250 3075);
FORCEADD OFFPAGE..6
(-8875 2875);
FORCEPROP 2 LAST $XR5 159 
J 0
(-9244 2911);
DISPLAY 0.638298 (-9244 2911);
PAINT MONO (-9244 2911);
FORCEPROP 2 LAST $XR4 103 
J 0
(-9364 2839);
DISPLAY 0.638298 (-9364 2839);
PAINT MONO (-9364 2839);
FORCEPROP 2 LAST $XR3 102 
J 0
(-9244 2839);
DISPLAY 0.638298 (-9244 2839);
PAINT MONO (-9244 2839);
FORCEPROP 2 LAST $XR2 101 
J 0
(-9364 2875);
DISPLAY 0.638298 (-9364 2875);
PAINT MONO (-9364 2875);
FORCEPROP 2 LAST $XR1 100 
J 0
(-9244 2875);
DISPLAY 0.638298 (-9244 2875);
PAINT MONO (-9244 2875);
FORCEPROP 2 LAST $XR0 98 
J 0
(-9124 2875);
DISPLAY 0.638298 (-9124 2875);
PAINT MONO (-9124 2875);
FORCEPROP 2 LAST CDS_LIB mstr_standard
J 0
(-8875 2875);
DISPLAY 0.808511 (-8875 2875);
DISPLAY INVISIBLE (-8875 2875);
FORCEPROP 1 LAST OFFPAGE TRUE
J 0
(-8550 2750);
DISPLAY 0.872340 (-8550 2750);
PAINT GREEN (-8550 2750);
DISPLAY INVISIBLE (-8550 2750);
FORCEPROP 1 LAST COMMENT_BODY TRUE
J 0
(-8775 2800);
DISPLAY 0.872340 (-8775 2800);
PAINT GREEN (-8775 2800);
DISPLAY INVISIBLE (-8775 2800);
FORCEPROP 2 LAST PATH I244
J 0
(-9150 2925);
DISPLAY 0.680851 (-9150 2925);
DISPLAY INVISIBLE (-9150 2925);
FORCEADD TAP..1
R 2
(-7775 3425);
FORCEPROP 3 LASTPIN (-7725 3425) SIG_NAME M_B_CPU1_SB_CB<2>
J 0
(-7715 3435);
DISPLAY 0.659574 (-7715 3435);
PAINT MONO (-7715 3435);
DISPLAY INVISIBLE (-7715 3435);
FORCEPROP 1 LASTPIN (-7725 3425) BN 2
J 2
(-7713 3433);
DISPLAY 0.489362 (-7713 3433);
PAINT GREEN (-7713 3433);
FORCEPROP 2 LAST CDS_LIB mstr_standard
J 0
(-7775 3425);
DISPLAY 0.723404 (-7775 3425);
PAINT MONO (-7775 3425);
DISPLAY INVISIBLE (-7775 3425);
FORCEPROP 1 LAST BODY_TYPE PLUMBING
J 2
(-7775 3475);
DISPLAY 0.872340 (-7775 3475);
PAINT GREEN (-7775 3475);
DISPLAY INVISIBLE (-7775 3475);
FORCEPROP 1 LAST HDL_TAP TRUE
J 2
(-8100 3300);
DISPLAY 0.872340 (-8100 3300);
DISPLAY INVISIBLE (-8100 3300);
FORCEPROP 1 LAST PATH I25
J 2
(-7773 3425);
DISPLAY 0.872340 (-7773 3425);
PAINT GREEN (-7773 3425);
DISPLAY INVISIBLE (-7773 3425);
FORCEADD TAP..1
R 2
(-7775 3525);
FORCEPROP 3 LASTPIN (-7725 3525) SIG_NAME M_B_CPU1_SB_CB<4>
J 0
(-7715 3535);
DISPLAY 0.659574 (-7715 3535);
PAINT MONO (-7715 3535);
DISPLAY INVISIBLE (-7715 3535);
FORCEPROP 1 LASTPIN (-7725 3525) BN 4
J 2
(-7713 3533);
DISPLAY 0.489362 (-7713 3533);
PAINT GREEN (-7713 3533);
FORCEPROP 2 LAST CDS_LIB mstr_standard
J 0
(-7775 3525);
DISPLAY 0.723404 (-7775 3525);
PAINT MONO (-7775 3525);
DISPLAY INVISIBLE (-7775 3525);
FORCEPROP 1 LAST BODY_TYPE PLUMBING
J 2
(-7775 3575);
DISPLAY 0.872340 (-7775 3575);
PAINT GREEN (-7775 3575);
DISPLAY INVISIBLE (-7775 3575);
FORCEPROP 1 LAST HDL_TAP TRUE
J 2
(-8100 3400);
DISPLAY 0.872340 (-8100 3400);
DISPLAY INVISIBLE (-8100 3400);
FORCEPROP 1 LAST PATH I26
J 2
(-7773 3525);
DISPLAY 0.872340 (-7773 3525);
PAINT GREEN (-7773 3525);
DISPLAY INVISIBLE (-7773 3525);
FORCEADD TAP..1
R 2
(-7775 3475);
FORCEPROP 3 LASTPIN (-7725 3475) SIG_NAME M_B_CPU1_SB_CB<3>
J 0
(-7715 3485);
DISPLAY 0.659574 (-7715 3485);
PAINT MONO (-7715 3485);
DISPLAY INVISIBLE (-7715 3485);
FORCEPROP 1 LASTPIN (-7725 3475) BN 3
J 2
(-7713 3483);
DISPLAY 0.489362 (-7713 3483);
PAINT GREEN (-7713 3483);
FORCEPROP 2 LAST CDS_LIB mstr_standard
J 0
(-7775 3475);
DISPLAY 0.723404 (-7775 3475);
PAINT MONO (-7775 3475);
DISPLAY INVISIBLE (-7775 3475);
FORCEPROP 1 LAST BODY_TYPE PLUMBING
J 2
(-7775 3525);
DISPLAY 0.872340 (-7775 3525);
PAINT GREEN (-7775 3525);
DISPLAY INVISIBLE (-7775 3525);
FORCEPROP 1 LAST HDL_TAP TRUE
J 2
(-8100 3350);
DISPLAY 0.872340 (-8100 3350);
DISPLAY INVISIBLE (-8100 3350);
FORCEPROP 1 LAST PATH I27
J 2
(-7773 3475);
DISPLAY 0.872340 (-7773 3475);
PAINT GREEN (-7773 3475);
DISPLAY INVISIBLE (-7773 3475);
FORCEADD TAP..1
R 2
(-7775 3575);
FORCEPROP 3 LASTPIN (-7725 3575) SIG_NAME M_B_CPU1_SB_CB<5>
J 0
(-7715 3585);
DISPLAY 0.659574 (-7715 3585);
PAINT MONO (-7715 3585);
DISPLAY INVISIBLE (-7715 3585);
FORCEPROP 1 LASTPIN (-7725 3575) BN 5
J 2
(-7713 3583);
DISPLAY 0.489362 (-7713 3583);
PAINT GREEN (-7713 3583);
FORCEPROP 2 LAST CDS_LIB mstr_standard
J 0
(-7775 3575);
DISPLAY 0.723404 (-7775 3575);
PAINT MONO (-7775 3575);
DISPLAY INVISIBLE (-7775 3575);
FORCEPROP 1 LAST BODY_TYPE PLUMBING
J 2
(-7775 3625);
DISPLAY 0.872340 (-7775 3625);
PAINT GREEN (-7775 3625);
DISPLAY INVISIBLE (-7775 3625);
FORCEPROP 1 LAST HDL_TAP TRUE
J 2
(-8100 3450);
DISPLAY 0.872340 (-8100 3450);
DISPLAY INVISIBLE (-8100 3450);
FORCEPROP 1 LAST PATH I28
J 2
(-7773 3575);
DISPLAY 0.872340 (-7773 3575);
PAINT GREEN (-7773 3575);
DISPLAY INVISIBLE (-7773 3575);
FORCEADD TAP..1
R 2
(-7775 3675);
FORCEPROP 3 LASTPIN (-7725 3675) SIG_NAME M_B_CPU1_SB_CB<7>
J 0
(-7715 3685);
DISPLAY 0.659574 (-7715 3685);
PAINT MONO (-7715 3685);
DISPLAY INVISIBLE (-7715 3685);
FORCEPROP 1 LASTPIN (-7725 3675) BN 7
J 2
(-7713 3683);
DISPLAY 0.489362 (-7713 3683);
PAINT GREEN (-7713 3683);
FORCEPROP 2 LAST CDS_LIB mstr_standard
J 0
(-7775 3675);
DISPLAY 0.723404 (-7775 3675);
PAINT MONO (-7775 3675);
DISPLAY INVISIBLE (-7775 3675);
FORCEPROP 1 LAST BODY_TYPE PLUMBING
J 2
(-7775 3725);
DISPLAY 0.872340 (-7775 3725);
PAINT GREEN (-7775 3725);
DISPLAY INVISIBLE (-7775 3725);
FORCEPROP 1 LAST HDL_TAP TRUE
J 2
(-8100 3550);
DISPLAY 0.872340 (-8100 3550);
DISPLAY INVISIBLE (-8100 3550);
FORCEPROP 1 LAST PATH I29
J 2
(-7773 3675);
DISPLAY 0.872340 (-7773 3675);
PAINT GREEN (-7773 3675);
DISPLAY INVISIBLE (-7773 3675);
FORCEADD TAP..1
R 2
(-7775 3625);
FORCEPROP 3 LASTPIN (-7725 3625) SIG_NAME M_B_CPU1_SB_CB<6>
J 0
(-7715 3635);
DISPLAY 0.659574 (-7715 3635);
PAINT MONO (-7715 3635);
DISPLAY INVISIBLE (-7715 3635);
FORCEPROP 1 LASTPIN (-7725 3625) BN 6
J 2
(-7713 3633);
DISPLAY 0.489362 (-7713 3633);
PAINT GREEN (-7713 3633);
FORCEPROP 2 LAST CDS_LIB mstr_standard
J 0
(-7775 3625);
DISPLAY 0.723404 (-7775 3625);
PAINT MONO (-7775 3625);
DISPLAY INVISIBLE (-7775 3625);
FORCEPROP 1 LAST BODY_TYPE PLUMBING
J 2
(-7775 3675);
DISPLAY 0.872340 (-7775 3675);
PAINT GREEN (-7775 3675);
DISPLAY INVISIBLE (-7775 3675);
FORCEPROP 1 LAST HDL_TAP TRUE
J 2
(-8100 3500);
DISPLAY 0.872340 (-8100 3500);
DISPLAY INVISIBLE (-8100 3500);
FORCEPROP 1 LAST PATH I30
J 2
(-7773 3625);
DISPLAY 0.872340 (-7773 3625);
PAINT GREEN (-7773 3625);
DISPLAY INVISIBLE (-7773 3625);
FORCEADD TAP..1
R 2
(-7775 3775);
FORCEPROP 3 LASTPIN (-7725 3775) SIG_NAME M_B_CPU1_SA_CB<0>
J 0
(-7715 3785);
DISPLAY 0.659574 (-7715 3785);
PAINT MONO (-7715 3785);
DISPLAY INVISIBLE (-7715 3785);
FORCEPROP 1 LASTPIN (-7725 3775) BN 0
J 2
(-7713 3783);
DISPLAY 0.489362 (-7713 3783);
PAINT GREEN (-7713 3783);
FORCEPROP 2 LAST CDS_LIB mstr_standard
J 0
(-7775 3775);
DISPLAY 0.723404 (-7775 3775);
PAINT MONO (-7775 3775);
DISPLAY INVISIBLE (-7775 3775);
FORCEPROP 1 LAST BODY_TYPE PLUMBING
J 2
(-7775 3825);
DISPLAY 0.872340 (-7775 3825);
PAINT GREEN (-7775 3825);
DISPLAY INVISIBLE (-7775 3825);
FORCEPROP 1 LAST HDL_TAP TRUE
J 2
(-8100 3650);
DISPLAY 0.872340 (-8100 3650);
DISPLAY INVISIBLE (-8100 3650);
FORCEPROP 1 LAST PATH I31
J 2
(-7773 3775);
DISPLAY 0.872340 (-7773 3775);
PAINT GREEN (-7773 3775);
DISPLAY INVISIBLE (-7773 3775);
FORCEADD TAP..1
R 2
(-7775 3825);
FORCEPROP 3 LASTPIN (-7725 3825) SIG_NAME M_B_CPU1_SA_CB<1>
J 0
(-7715 3835);
DISPLAY 0.659574 (-7715 3835);
PAINT MONO (-7715 3835);
DISPLAY INVISIBLE (-7715 3835);
FORCEPROP 1 LASTPIN (-7725 3825) BN 1
J 2
(-7713 3833);
DISPLAY 0.489362 (-7713 3833);
PAINT GREEN (-7713 3833);
FORCEPROP 2 LAST CDS_LIB mstr_standard
J 0
(-7775 3825);
DISPLAY 0.723404 (-7775 3825);
PAINT MONO (-7775 3825);
DISPLAY INVISIBLE (-7775 3825);
FORCEPROP 1 LAST BODY_TYPE PLUMBING
J 2
(-7775 3875);
DISPLAY 0.872340 (-7775 3875);
PAINT GREEN (-7775 3875);
DISPLAY INVISIBLE (-7775 3875);
FORCEPROP 1 LAST HDL_TAP TRUE
J 2
(-8100 3700);
DISPLAY 0.872340 (-8100 3700);
DISPLAY INVISIBLE (-8100 3700);
FORCEPROP 1 LAST PATH I32
J 2
(-7773 3825);
DISPLAY 0.872340 (-7773 3825);
PAINT GREEN (-7773 3825);
DISPLAY INVISIBLE (-7773 3825);
FORCEADD TAP..1
R 2
(-7775 3875);
FORCEPROP 3 LASTPIN (-7725 3875) SIG_NAME M_B_CPU1_SA_CB<2>
J 0
(-7715 3885);
DISPLAY 0.659574 (-7715 3885);
PAINT MONO (-7715 3885);
DISPLAY INVISIBLE (-7715 3885);
FORCEPROP 1 LASTPIN (-7725 3875) BN 2
J 2
(-7713 3883);
DISPLAY 0.489362 (-7713 3883);
PAINT GREEN (-7713 3883);
FORCEPROP 2 LAST CDS_LIB mstr_standard
J 0
(-7775 3875);
DISPLAY 0.723404 (-7775 3875);
PAINT MONO (-7775 3875);
DISPLAY INVISIBLE (-7775 3875);
FORCEPROP 1 LAST BODY_TYPE PLUMBING
J 2
(-7775 3925);
DISPLAY 0.872340 (-7775 3925);
PAINT GREEN (-7775 3925);
DISPLAY INVISIBLE (-7775 3925);
FORCEPROP 1 LAST HDL_TAP TRUE
J 2
(-8100 3750);
DISPLAY 0.872340 (-8100 3750);
DISPLAY INVISIBLE (-8100 3750);
FORCEPROP 1 LAST PATH I33
J 2
(-7773 3875);
DISPLAY 0.872340 (-7773 3875);
PAINT GREEN (-7773 3875);
DISPLAY INVISIBLE (-7773 3875);
FORCEADD TAP..1
R 2
(-7775 3925);
FORCEPROP 3 LASTPIN (-7725 3925) SIG_NAME M_B_CPU1_SA_CB<3>
J 0
(-7715 3935);
DISPLAY 0.659574 (-7715 3935);
PAINT MONO (-7715 3935);
DISPLAY INVISIBLE (-7715 3935);
FORCEPROP 1 LASTPIN (-7725 3925) BN 3
J 2
(-7713 3933);
DISPLAY 0.489362 (-7713 3933);
PAINT GREEN (-7713 3933);
FORCEPROP 2 LAST CDS_LIB mstr_standard
J 0
(-7775 3925);
DISPLAY 0.723404 (-7775 3925);
PAINT MONO (-7775 3925);
DISPLAY INVISIBLE (-7775 3925);
FORCEPROP 1 LAST BODY_TYPE PLUMBING
J 2
(-7775 3975);
DISPLAY 0.872340 (-7775 3975);
PAINT GREEN (-7775 3975);
DISPLAY INVISIBLE (-7775 3975);
FORCEPROP 1 LAST HDL_TAP TRUE
J 2
(-8100 3800);
DISPLAY 0.872340 (-8100 3800);
DISPLAY INVISIBLE (-8100 3800);
FORCEPROP 1 LAST PATH I34
J 2
(-7773 3925);
DISPLAY 0.872340 (-7773 3925);
PAINT GREEN (-7773 3925);
DISPLAY INVISIBLE (-7773 3925);
FORCEADD TAP..1
R 2
(-7775 4025);
FORCEPROP 3 LASTPIN (-7725 4025) SIG_NAME M_B_CPU1_SA_CB<5>
J 0
(-7715 4035);
DISPLAY 0.659574 (-7715 4035);
PAINT MONO (-7715 4035);
DISPLAY INVISIBLE (-7715 4035);
FORCEPROP 1 LASTPIN (-7725 4025) BN 5
J 2
(-7713 4033);
DISPLAY 0.489362 (-7713 4033);
PAINT GREEN (-7713 4033);
FORCEPROP 2 LAST CDS_LIB mstr_standard
J 0
(-7775 4025);
DISPLAY 0.723404 (-7775 4025);
PAINT MONO (-7775 4025);
DISPLAY INVISIBLE (-7775 4025);
FORCEPROP 1 LAST BODY_TYPE PLUMBING
J 2
(-7775 4075);
DISPLAY 0.872340 (-7775 4075);
PAINT GREEN (-7775 4075);
DISPLAY INVISIBLE (-7775 4075);
FORCEPROP 1 LAST HDL_TAP TRUE
J 2
(-8100 3900);
DISPLAY 0.872340 (-8100 3900);
DISPLAY INVISIBLE (-8100 3900);
FORCEPROP 1 LAST PATH I35
J 2
(-7773 4025);
DISPLAY 0.872340 (-7773 4025);
PAINT GREEN (-7773 4025);
DISPLAY INVISIBLE (-7773 4025);
FORCEADD TAP..1
R 2
(-7775 3975);
FORCEPROP 3 LASTPIN (-7725 3975) SIG_NAME M_B_CPU1_SA_CB<4>
J 0
(-7715 3985);
DISPLAY 0.659574 (-7715 3985);
PAINT MONO (-7715 3985);
DISPLAY INVISIBLE (-7715 3985);
FORCEPROP 1 LASTPIN (-7725 3975) BN 4
J 2
(-7713 3983);
DISPLAY 0.489362 (-7713 3983);
PAINT GREEN (-7713 3983);
FORCEPROP 2 LAST CDS_LIB mstr_standard
J 0
(-7775 3975);
DISPLAY 0.723404 (-7775 3975);
PAINT MONO (-7775 3975);
DISPLAY INVISIBLE (-7775 3975);
FORCEPROP 1 LAST BODY_TYPE PLUMBING
J 2
(-7775 4025);
DISPLAY 0.872340 (-7775 4025);
PAINT GREEN (-7775 4025);
DISPLAY INVISIBLE (-7775 4025);
FORCEPROP 1 LAST HDL_TAP TRUE
J 2
(-8100 3850);
DISPLAY 0.872340 (-8100 3850);
DISPLAY INVISIBLE (-8100 3850);
FORCEPROP 1 LAST PATH I36
J 2
(-7773 3975);
DISPLAY 0.872340 (-7773 3975);
PAINT GREEN (-7773 3975);
DISPLAY INVISIBLE (-7773 3975);
FORCEADD TAP..1
R 2
(-7775 4075);
FORCEPROP 3 LASTPIN (-7725 4075) SIG_NAME M_B_CPU1_SA_CB<6>
J 0
(-7715 4085);
DISPLAY 0.659574 (-7715 4085);
PAINT MONO (-7715 4085);
DISPLAY INVISIBLE (-7715 4085);
FORCEPROP 1 LASTPIN (-7725 4075) BN 6
J 2
(-7713 4083);
DISPLAY 0.489362 (-7713 4083);
PAINT GREEN (-7713 4083);
FORCEPROP 2 LAST CDS_LIB mstr_standard
J 0
(-7775 4075);
DISPLAY 0.723404 (-7775 4075);
PAINT MONO (-7775 4075);
DISPLAY INVISIBLE (-7775 4075);
FORCEPROP 1 LAST BODY_TYPE PLUMBING
J 2
(-7775 4125);
DISPLAY 0.872340 (-7775 4125);
PAINT GREEN (-7775 4125);
DISPLAY INVISIBLE (-7775 4125);
FORCEPROP 1 LAST HDL_TAP TRUE
J 2
(-8100 3950);
DISPLAY 0.872340 (-8100 3950);
DISPLAY INVISIBLE (-8100 3950);
FORCEPROP 1 LAST PATH I37
J 2
(-7773 4075);
DISPLAY 0.872340 (-7773 4075);
PAINT GREEN (-7773 4075);
DISPLAY INVISIBLE (-7773 4075);
FORCEADD TAP..1
(-6075 2375);
FORCEPROP 3 LASTPIN (-6125 2375) SIG_NAME M_B_CPU1_SB_DQ<1>
J 0
(-6115 2385);
DISPLAY 0.659574 (-6115 2385);
PAINT MONO (-6115 2385);
DISPLAY INVISIBLE (-6115 2385);
FORCEPROP 1 LASTPIN (-6125 2375) BN 1
J 0
(-6137 2383);
DISPLAY 0.489362 (-6137 2383);
PAINT GREEN (-6137 2383);
FORCEPROP 2 LAST CDS_LIB mstr_standard
J 0
(-6075 2375);
DISPLAY 0.723404 (-6075 2375);
PAINT MONO (-6075 2375);
DISPLAY INVISIBLE (-6075 2375);
FORCEPROP 1 LAST BODY_TYPE PLUMBING
J 0
(-6075 2425);
DISPLAY 0.872340 (-6075 2425);
PAINT GREEN (-6075 2425);
DISPLAY INVISIBLE (-6075 2425);
FORCEPROP 1 LAST HDL_TAP TRUE
J 0
(-5750 2250);
DISPLAY 0.872340 (-5750 2250);
DISPLAY INVISIBLE (-5750 2250);
FORCEPROP 1 LAST PATH I38
J 0
(-6077 2375);
DISPLAY 0.872340 (-6077 2375);
PAINT GREEN (-6077 2375);
DISPLAY INVISIBLE (-6077 2375);
FORCEADD TAP..1
(-6075 2325);
FORCEPROP 3 LASTPIN (-6125 2325) SIG_NAME M_B_CPU1_SB_DQ<0>
J 0
(-6115 2335);
DISPLAY 0.659574 (-6115 2335);
PAINT MONO (-6115 2335);
DISPLAY INVISIBLE (-6115 2335);
FORCEPROP 1 LASTPIN (-6125 2325) BN 0
J 0
(-6137 2333);
DISPLAY 0.489362 (-6137 2333);
PAINT GREEN (-6137 2333);
FORCEPROP 2 LAST CDS_LIB mstr_standard
J 0
(-6075 2325);
DISPLAY 0.723404 (-6075 2325);
PAINT MONO (-6075 2325);
DISPLAY INVISIBLE (-6075 2325);
FORCEPROP 1 LAST BODY_TYPE PLUMBING
J 0
(-6075 2375);
DISPLAY 0.872340 (-6075 2375);
PAINT GREEN (-6075 2375);
DISPLAY INVISIBLE (-6075 2375);
FORCEPROP 1 LAST HDL_TAP TRUE
J 0
(-5750 2200);
DISPLAY 0.872340 (-5750 2200);
DISPLAY INVISIBLE (-5750 2200);
FORCEPROP 1 LAST PATH I39
J 0
(-6077 2325);
DISPLAY 0.872340 (-6077 2325);
PAINT GREEN (-6077 2325);
DISPLAY INVISIBLE (-6077 2325);
FORCEADD TAP..1
(-6075 2425);
FORCEPROP 3 LASTPIN (-6125 2425) SIG_NAME M_B_CPU1_SB_DQ<2>
J 0
(-6115 2435);
DISPLAY 0.659574 (-6115 2435);
PAINT MONO (-6115 2435);
DISPLAY INVISIBLE (-6115 2435);
FORCEPROP 1 LASTPIN (-6125 2425) BN 2
J 0
(-6137 2433);
DISPLAY 0.489362 (-6137 2433);
PAINT GREEN (-6137 2433);
FORCEPROP 2 LAST CDS_LIB mstr_standard
J 0
(-6075 2425);
DISPLAY 0.723404 (-6075 2425);
PAINT MONO (-6075 2425);
DISPLAY INVISIBLE (-6075 2425);
FORCEPROP 1 LAST BODY_TYPE PLUMBING
J 0
(-6075 2475);
DISPLAY 0.872340 (-6075 2475);
PAINT GREEN (-6075 2475);
DISPLAY INVISIBLE (-6075 2475);
FORCEPROP 1 LAST HDL_TAP TRUE
J 0
(-5750 2300);
DISPLAY 0.872340 (-5750 2300);
DISPLAY INVISIBLE (-5750 2300);
FORCEPROP 1 LAST PATH I40
J 0
(-6077 2425);
DISPLAY 0.872340 (-6077 2425);
PAINT GREEN (-6077 2425);
DISPLAY INVISIBLE (-6077 2425);
FORCEADD TAP..1
(-6075 2475);
FORCEPROP 3 LASTPIN (-6125 2475) SIG_NAME M_B_CPU1_SB_DQ<3>
J 0
(-6115 2485);
DISPLAY 0.659574 (-6115 2485);
PAINT MONO (-6115 2485);
DISPLAY INVISIBLE (-6115 2485);
FORCEPROP 1 LASTPIN (-6125 2475) BN 3
J 0
(-6137 2483);
DISPLAY 0.489362 (-6137 2483);
PAINT GREEN (-6137 2483);
FORCEPROP 2 LAST CDS_LIB mstr_standard
J 0
(-6075 2475);
DISPLAY 0.723404 (-6075 2475);
PAINT MONO (-6075 2475);
DISPLAY INVISIBLE (-6075 2475);
FORCEPROP 1 LAST BODY_TYPE PLUMBING
J 0
(-6075 2525);
DISPLAY 0.872340 (-6075 2525);
PAINT GREEN (-6075 2525);
DISPLAY INVISIBLE (-6075 2525);
FORCEPROP 1 LAST HDL_TAP TRUE
J 0
(-5750 2350);
DISPLAY 0.872340 (-5750 2350);
DISPLAY INVISIBLE (-5750 2350);
FORCEPROP 1 LAST PATH I41
J 0
(-6077 2475);
DISPLAY 0.872340 (-6077 2475);
PAINT GREEN (-6077 2475);
DISPLAY INVISIBLE (-6077 2475);
FORCEADD TAP..1
(-6075 2525);
FORCEPROP 3 LASTPIN (-6125 2525) SIG_NAME M_B_CPU1_SB_DQ<4>
J 0
(-6115 2535);
DISPLAY 0.659574 (-6115 2535);
PAINT MONO (-6115 2535);
DISPLAY INVISIBLE (-6115 2535);
FORCEPROP 1 LASTPIN (-6125 2525) BN 4
J 0
(-6137 2533);
DISPLAY 0.489362 (-6137 2533);
PAINT GREEN (-6137 2533);
FORCEPROP 2 LAST CDS_LIB mstr_standard
J 0
(-6075 2525);
DISPLAY 0.723404 (-6075 2525);
PAINT MONO (-6075 2525);
DISPLAY INVISIBLE (-6075 2525);
FORCEPROP 1 LAST BODY_TYPE PLUMBING
J 0
(-6075 2575);
DISPLAY 0.872340 (-6075 2575);
PAINT GREEN (-6075 2575);
DISPLAY INVISIBLE (-6075 2575);
FORCEPROP 1 LAST HDL_TAP TRUE
J 0
(-5750 2400);
DISPLAY 0.872340 (-5750 2400);
DISPLAY INVISIBLE (-5750 2400);
FORCEPROP 1 LAST PATH I42
J 0
(-6077 2525);
DISPLAY 0.872340 (-6077 2525);
PAINT GREEN (-6077 2525);
DISPLAY INVISIBLE (-6077 2525);
FORCEADD TAP..1
(-6075 2575);
FORCEPROP 3 LASTPIN (-6125 2575) SIG_NAME M_B_CPU1_SB_DQ<5>
J 0
(-6115 2585);
DISPLAY 0.659574 (-6115 2585);
PAINT MONO (-6115 2585);
DISPLAY INVISIBLE (-6115 2585);
FORCEPROP 1 LASTPIN (-6125 2575) BN 5
J 0
(-6137 2583);
DISPLAY 0.489362 (-6137 2583);
PAINT GREEN (-6137 2583);
FORCEPROP 2 LAST CDS_LIB mstr_standard
J 0
(-6075 2575);
DISPLAY 0.723404 (-6075 2575);
PAINT MONO (-6075 2575);
DISPLAY INVISIBLE (-6075 2575);
FORCEPROP 1 LAST BODY_TYPE PLUMBING
J 0
(-6075 2625);
DISPLAY 0.872340 (-6075 2625);
PAINT GREEN (-6075 2625);
DISPLAY INVISIBLE (-6075 2625);
FORCEPROP 1 LAST HDL_TAP TRUE
J 0
(-5750 2450);
DISPLAY 0.872340 (-5750 2450);
DISPLAY INVISIBLE (-5750 2450);
FORCEPROP 1 LAST PATH I43
J 0
(-6077 2575);
DISPLAY 0.872340 (-6077 2575);
PAINT GREEN (-6077 2575);
DISPLAY INVISIBLE (-6077 2575);
FORCEADD TAP..1
(-6075 2675);
FORCEPROP 3 LASTPIN (-6125 2675) SIG_NAME M_B_CPU1_SB_DQ<7>
J 0
(-6115 2685);
DISPLAY 0.659574 (-6115 2685);
PAINT MONO (-6115 2685);
DISPLAY INVISIBLE (-6115 2685);
FORCEPROP 1 LASTPIN (-6125 2675) BN 7
J 0
(-6137 2683);
DISPLAY 0.489362 (-6137 2683);
PAINT GREEN (-6137 2683);
FORCEPROP 2 LAST CDS_LIB mstr_standard
J 0
(-6075 2675);
DISPLAY 0.723404 (-6075 2675);
PAINT MONO (-6075 2675);
DISPLAY INVISIBLE (-6075 2675);
FORCEPROP 1 LAST BODY_TYPE PLUMBING
J 0
(-6075 2725);
DISPLAY 0.872340 (-6075 2725);
PAINT GREEN (-6075 2725);
DISPLAY INVISIBLE (-6075 2725);
FORCEPROP 1 LAST HDL_TAP TRUE
J 0
(-5750 2550);
DISPLAY 0.872340 (-5750 2550);
DISPLAY INVISIBLE (-5750 2550);
FORCEPROP 1 LAST PATH I44
J 0
(-6077 2675);
DISPLAY 0.872340 (-6077 2675);
PAINT GREEN (-6077 2675);
DISPLAY INVISIBLE (-6077 2675);
FORCEADD TAP..1
(-6075 2625);
FORCEPROP 3 LASTPIN (-6125 2625) SIG_NAME M_B_CPU1_SB_DQ<6>
J 0
(-6115 2635);
DISPLAY 0.659574 (-6115 2635);
PAINT MONO (-6115 2635);
DISPLAY INVISIBLE (-6115 2635);
FORCEPROP 1 LASTPIN (-6125 2625) BN 6
J 0
(-6137 2633);
DISPLAY 0.489362 (-6137 2633);
PAINT GREEN (-6137 2633);
FORCEPROP 2 LAST CDS_LIB mstr_standard
J 0
(-6075 2625);
DISPLAY 0.723404 (-6075 2625);
PAINT MONO (-6075 2625);
DISPLAY INVISIBLE (-6075 2625);
FORCEPROP 1 LAST BODY_TYPE PLUMBING
J 0
(-6075 2675);
DISPLAY 0.872340 (-6075 2675);
PAINT GREEN (-6075 2675);
DISPLAY INVISIBLE (-6075 2675);
FORCEPROP 1 LAST HDL_TAP TRUE
J 0
(-5750 2500);
DISPLAY 0.872340 (-5750 2500);
DISPLAY INVISIBLE (-5750 2500);
FORCEPROP 1 LAST PATH I45
J 0
(-6077 2625);
DISPLAY 0.872340 (-6077 2625);
PAINT GREEN (-6077 2625);
DISPLAY INVISIBLE (-6077 2625);
FORCEADD TAP..1
(-6075 2775);
FORCEPROP 3 LASTPIN (-6125 2775) SIG_NAME M_B_CPU1_SB_DQ<9>
J 0
(-6115 2785);
DISPLAY 0.659574 (-6115 2785);
PAINT MONO (-6115 2785);
DISPLAY INVISIBLE (-6115 2785);
FORCEPROP 1 LASTPIN (-6125 2775) BN 9
J 0
(-6137 2783);
DISPLAY 0.489362 (-6137 2783);
PAINT GREEN (-6137 2783);
FORCEPROP 2 LAST CDS_LIB mstr_standard
J 0
(-6075 2775);
DISPLAY 0.723404 (-6075 2775);
PAINT MONO (-6075 2775);
DISPLAY INVISIBLE (-6075 2775);
FORCEPROP 1 LAST BODY_TYPE PLUMBING
J 0
(-6075 2825);
DISPLAY 0.872340 (-6075 2825);
PAINT GREEN (-6075 2825);
DISPLAY INVISIBLE (-6075 2825);
FORCEPROP 1 LAST HDL_TAP TRUE
J 0
(-5750 2650);
DISPLAY 0.872340 (-5750 2650);
DISPLAY INVISIBLE (-5750 2650);
FORCEPROP 1 LAST PATH I46
J 0
(-6077 2775);
DISPLAY 0.872340 (-6077 2775);
PAINT GREEN (-6077 2775);
DISPLAY INVISIBLE (-6077 2775);
FORCEADD TAP..1
(-6075 2725);
FORCEPROP 3 LASTPIN (-6125 2725) SIG_NAME M_B_CPU1_SB_DQ<8>
J 0
(-6115 2735);
DISPLAY 0.659574 (-6115 2735);
PAINT MONO (-6115 2735);
DISPLAY INVISIBLE (-6115 2735);
FORCEPROP 1 LASTPIN (-6125 2725) BN 8
J 0
(-6137 2733);
DISPLAY 0.489362 (-6137 2733);
PAINT GREEN (-6137 2733);
FORCEPROP 2 LAST CDS_LIB mstr_standard
J 0
(-6075 2725);
DISPLAY 0.723404 (-6075 2725);
PAINT MONO (-6075 2725);
DISPLAY INVISIBLE (-6075 2725);
FORCEPROP 1 LAST BODY_TYPE PLUMBING
J 0
(-6075 2775);
DISPLAY 0.872340 (-6075 2775);
PAINT GREEN (-6075 2775);
DISPLAY INVISIBLE (-6075 2775);
FORCEPROP 1 LAST HDL_TAP TRUE
J 0
(-5750 2600);
DISPLAY 0.872340 (-5750 2600);
DISPLAY INVISIBLE (-5750 2600);
FORCEPROP 1 LAST PATH I47
J 0
(-6077 2725);
DISPLAY 0.872340 (-6077 2725);
PAINT GREEN (-6077 2725);
DISPLAY INVISIBLE (-6077 2725);
FORCEADD TAP..1
(-6075 2975);
FORCEPROP 3 LASTPIN (-6125 2975) SIG_NAME M_B_CPU1_SB_DQ<13>
J 0
(-6115 2985);
DISPLAY 0.659574 (-6115 2985);
PAINT MONO (-6115 2985);
DISPLAY INVISIBLE (-6115 2985);
FORCEPROP 1 LASTPIN (-6125 2975) BN 13
J 0
(-6137 2983);
DISPLAY 0.489362 (-6137 2983);
PAINT GREEN (-6137 2983);
FORCEPROP 2 LAST CDS_LIB mstr_standard
J 0
(-6075 2975);
DISPLAY 0.723404 (-6075 2975);
PAINT MONO (-6075 2975);
DISPLAY INVISIBLE (-6075 2975);
FORCEPROP 1 LAST BODY_TYPE PLUMBING
J 0
(-6075 3025);
DISPLAY 0.872340 (-6075 3025);
PAINT GREEN (-6075 3025);
DISPLAY INVISIBLE (-6075 3025);
FORCEPROP 1 LAST HDL_TAP TRUE
J 0
(-5750 2850);
DISPLAY 0.872340 (-5750 2850);
DISPLAY INVISIBLE (-5750 2850);
FORCEPROP 1 LAST PATH I48
J 0
(-6077 2975);
DISPLAY 0.872340 (-6077 2975);
PAINT GREEN (-6077 2975);
DISPLAY INVISIBLE (-6077 2975);
FORCEADD TAP..1
(-6075 3025);
FORCEPROP 3 LASTPIN (-6125 3025) SIG_NAME M_B_CPU1_SB_DQ<14>
J 0
(-6115 3035);
DISPLAY 0.659574 (-6115 3035);
PAINT MONO (-6115 3035);
DISPLAY INVISIBLE (-6115 3035);
FORCEPROP 1 LASTPIN (-6125 3025) BN 14
J 0
(-6137 3033);
DISPLAY 0.489362 (-6137 3033);
PAINT GREEN (-6137 3033);
FORCEPROP 2 LAST CDS_LIB mstr_standard
J 0
(-6075 3025);
DISPLAY 0.723404 (-6075 3025);
PAINT MONO (-6075 3025);
DISPLAY INVISIBLE (-6075 3025);
FORCEPROP 1 LAST BODY_TYPE PLUMBING
J 0
(-6075 3075);
DISPLAY 0.872340 (-6075 3075);
PAINT GREEN (-6075 3075);
DISPLAY INVISIBLE (-6075 3075);
FORCEPROP 1 LAST HDL_TAP TRUE
J 0
(-5750 2900);
DISPLAY 0.872340 (-5750 2900);
DISPLAY INVISIBLE (-5750 2900);
FORCEPROP 1 LAST PATH I49
J 0
(-6077 3025);
DISPLAY 0.872340 (-6077 3025);
PAINT GREEN (-6077 3025);
DISPLAY INVISIBLE (-6077 3025);
FORCEADD TAP..1
(-6075 2925);
FORCEPROP 3 LASTPIN (-6125 2925) SIG_NAME M_B_CPU1_SB_DQ<12>
J 0
(-6115 2935);
DISPLAY 0.659574 (-6115 2935);
PAINT MONO (-6115 2935);
DISPLAY INVISIBLE (-6115 2935);
FORCEPROP 1 LASTPIN (-6125 2925) BN 12
J 0
(-6137 2933);
DISPLAY 0.489362 (-6137 2933);
PAINT GREEN (-6137 2933);
FORCEPROP 2 LAST CDS_LIB mstr_standard
J 0
(-6075 2925);
DISPLAY 0.723404 (-6075 2925);
PAINT MONO (-6075 2925);
DISPLAY INVISIBLE (-6075 2925);
FORCEPROP 1 LAST BODY_TYPE PLUMBING
J 0
(-6075 2975);
DISPLAY 0.872340 (-6075 2975);
PAINT GREEN (-6075 2975);
DISPLAY INVISIBLE (-6075 2975);
FORCEPROP 1 LAST HDL_TAP TRUE
J 0
(-5750 2800);
DISPLAY 0.872340 (-5750 2800);
DISPLAY INVISIBLE (-5750 2800);
FORCEPROP 1 LAST PATH I50
J 0
(-6077 2925);
DISPLAY 0.872340 (-6077 2925);
PAINT GREEN (-6077 2925);
DISPLAY INVISIBLE (-6077 2925);
FORCEADD TAP..1
(-6075 2875);
FORCEPROP 3 LASTPIN (-6125 2875) SIG_NAME M_B_CPU1_SB_DQ<11>
J 0
(-6115 2885);
DISPLAY 0.659574 (-6115 2885);
PAINT MONO (-6115 2885);
DISPLAY INVISIBLE (-6115 2885);
FORCEPROP 1 LASTPIN (-6125 2875) BN 11
J 0
(-6137 2883);
DISPLAY 0.489362 (-6137 2883);
PAINT GREEN (-6137 2883);
FORCEPROP 2 LAST CDS_LIB mstr_standard
J 0
(-6075 2875);
DISPLAY 0.723404 (-6075 2875);
PAINT MONO (-6075 2875);
DISPLAY INVISIBLE (-6075 2875);
FORCEPROP 1 LAST BODY_TYPE PLUMBING
J 0
(-6075 2925);
DISPLAY 0.872340 (-6075 2925);
PAINT GREEN (-6075 2925);
DISPLAY INVISIBLE (-6075 2925);
FORCEPROP 1 LAST HDL_TAP TRUE
J 0
(-5750 2750);
DISPLAY 0.872340 (-5750 2750);
DISPLAY INVISIBLE (-5750 2750);
FORCEPROP 1 LAST PATH I51
J 0
(-6077 2875);
DISPLAY 0.872340 (-6077 2875);
PAINT GREEN (-6077 2875);
DISPLAY INVISIBLE (-6077 2875);
FORCEADD TAP..1
(-6075 2825);
FORCEPROP 3 LASTPIN (-6125 2825) SIG_NAME M_B_CPU1_SB_DQ<10>
J 0
(-6115 2835);
DISPLAY 0.659574 (-6115 2835);
PAINT MONO (-6115 2835);
DISPLAY INVISIBLE (-6115 2835);
FORCEPROP 1 LASTPIN (-6125 2825) BN 10
J 0
(-6137 2833);
DISPLAY 0.489362 (-6137 2833);
PAINT GREEN (-6137 2833);
FORCEPROP 2 LAST CDS_LIB mstr_standard
J 0
(-6075 2825);
DISPLAY 0.723404 (-6075 2825);
PAINT MONO (-6075 2825);
DISPLAY INVISIBLE (-6075 2825);
FORCEPROP 1 LAST BODY_TYPE PLUMBING
J 0
(-6075 2875);
DISPLAY 0.872340 (-6075 2875);
PAINT GREEN (-6075 2875);
DISPLAY INVISIBLE (-6075 2875);
FORCEPROP 1 LAST HDL_TAP TRUE
J 0
(-5750 2700);
DISPLAY 0.872340 (-5750 2700);
DISPLAY INVISIBLE (-5750 2700);
FORCEPROP 1 LAST PATH I52
J 0
(-6077 2825);
DISPLAY 0.872340 (-6077 2825);
PAINT GREEN (-6077 2825);
DISPLAY INVISIBLE (-6077 2825);
FORCEADD TAP..1
(-6075 3075);
FORCEPROP 3 LASTPIN (-6125 3075) SIG_NAME M_B_CPU1_SB_DQ<15>
J 0
(-6115 3085);
DISPLAY 0.659574 (-6115 3085);
PAINT MONO (-6115 3085);
DISPLAY INVISIBLE (-6115 3085);
FORCEPROP 1 LASTPIN (-6125 3075) BN 15
J 0
(-6137 3083);
DISPLAY 0.489362 (-6137 3083);
PAINT GREEN (-6137 3083);
FORCEPROP 2 LAST CDS_LIB mstr_standard
J 0
(-6075 3075);
DISPLAY 0.723404 (-6075 3075);
PAINT MONO (-6075 3075);
DISPLAY INVISIBLE (-6075 3075);
FORCEPROP 1 LAST BODY_TYPE PLUMBING
J 0
(-6075 3125);
DISPLAY 0.872340 (-6075 3125);
PAINT GREEN (-6075 3125);
DISPLAY INVISIBLE (-6075 3125);
FORCEPROP 1 LAST HDL_TAP TRUE
J 0
(-5750 2950);
DISPLAY 0.872340 (-5750 2950);
DISPLAY INVISIBLE (-5750 2950);
FORCEPROP 1 LAST PATH I53
J 0
(-6077 3075);
DISPLAY 0.872340 (-6077 3075);
PAINT GREEN (-6077 3075);
DISPLAY INVISIBLE (-6077 3075);
FORCEADD TAP..1
(-6075 3175);
FORCEPROP 3 LASTPIN (-6125 3175) SIG_NAME M_B_CPU1_SB_DQ<17>
J 0
(-6115 3185);
DISPLAY 0.659574 (-6115 3185);
PAINT MONO (-6115 3185);
DISPLAY INVISIBLE (-6115 3185);
FORCEPROP 1 LASTPIN (-6125 3175) BN 17
J 0
(-6137 3183);
DISPLAY 0.489362 (-6137 3183);
PAINT GREEN (-6137 3183);
FORCEPROP 2 LAST CDS_LIB mstr_standard
J 0
(-6075 3175);
DISPLAY 0.723404 (-6075 3175);
PAINT MONO (-6075 3175);
DISPLAY INVISIBLE (-6075 3175);
FORCEPROP 1 LAST BODY_TYPE PLUMBING
J 0
(-6075 3225);
DISPLAY 0.872340 (-6075 3225);
PAINT GREEN (-6075 3225);
DISPLAY INVISIBLE (-6075 3225);
FORCEPROP 1 LAST HDL_TAP TRUE
J 0
(-5750 3050);
DISPLAY 0.872340 (-5750 3050);
DISPLAY INVISIBLE (-5750 3050);
FORCEPROP 1 LAST PATH I54
J 0
(-6077 3175);
DISPLAY 0.872340 (-6077 3175);
PAINT GREEN (-6077 3175);
DISPLAY INVISIBLE (-6077 3175);
FORCEADD TAP..1
(-6075 3125);
FORCEPROP 3 LASTPIN (-6125 3125) SIG_NAME M_B_CPU1_SB_DQ<16>
J 0
(-6115 3135);
DISPLAY 0.659574 (-6115 3135);
PAINT MONO (-6115 3135);
DISPLAY INVISIBLE (-6115 3135);
FORCEPROP 1 LASTPIN (-6125 3125) BN 16
J 0
(-6137 3133);
DISPLAY 0.489362 (-6137 3133);
PAINT GREEN (-6137 3133);
FORCEPROP 2 LAST CDS_LIB mstr_standard
J 0
(-6075 3125);
DISPLAY 0.723404 (-6075 3125);
PAINT MONO (-6075 3125);
DISPLAY INVISIBLE (-6075 3125);
FORCEPROP 1 LAST BODY_TYPE PLUMBING
J 0
(-6075 3175);
DISPLAY 0.872340 (-6075 3175);
PAINT GREEN (-6075 3175);
DISPLAY INVISIBLE (-6075 3175);
FORCEPROP 1 LAST HDL_TAP TRUE
J 0
(-5750 3000);
DISPLAY 0.872340 (-5750 3000);
DISPLAY INVISIBLE (-5750 3000);
FORCEPROP 1 LAST PATH I55
J 0
(-6077 3125);
DISPLAY 0.872340 (-6077 3125);
PAINT GREEN (-6077 3125);
DISPLAY INVISIBLE (-6077 3125);
FORCEADD TAP..1
(-6075 3225);
FORCEPROP 3 LASTPIN (-6125 3225) SIG_NAME M_B_CPU1_SB_DQ<18>
J 0
(-6115 3235);
DISPLAY 0.659574 (-6115 3235);
PAINT MONO (-6115 3235);
DISPLAY INVISIBLE (-6115 3235);
FORCEPROP 1 LASTPIN (-6125 3225) BN 18
J 0
(-6137 3233);
DISPLAY 0.489362 (-6137 3233);
PAINT GREEN (-6137 3233);
FORCEPROP 2 LAST CDS_LIB mstr_standard
J 0
(-6075 3225);
DISPLAY 0.723404 (-6075 3225);
PAINT MONO (-6075 3225);
DISPLAY INVISIBLE (-6075 3225);
FORCEPROP 1 LAST BODY_TYPE PLUMBING
J 0
(-6075 3275);
DISPLAY 0.872340 (-6075 3275);
PAINT GREEN (-6075 3275);
DISPLAY INVISIBLE (-6075 3275);
FORCEPROP 1 LAST HDL_TAP TRUE
J 0
(-5750 3100);
DISPLAY 0.872340 (-5750 3100);
DISPLAY INVISIBLE (-5750 3100);
FORCEPROP 1 LAST PATH I56
J 0
(-6077 3225);
DISPLAY 0.872340 (-6077 3225);
PAINT GREEN (-6077 3225);
DISPLAY INVISIBLE (-6077 3225);
FORCEADD TAP..1
(-6075 3275);
FORCEPROP 3 LASTPIN (-6125 3275) SIG_NAME M_B_CPU1_SB_DQ<19>
J 0
(-6115 3285);
DISPLAY 0.659574 (-6115 3285);
PAINT MONO (-6115 3285);
DISPLAY INVISIBLE (-6115 3285);
FORCEPROP 1 LASTPIN (-6125 3275) BN 19
J 0
(-6137 3283);
DISPLAY 0.489362 (-6137 3283);
PAINT GREEN (-6137 3283);
FORCEPROP 2 LAST CDS_LIB mstr_standard
J 0
(-6075 3275);
DISPLAY 0.723404 (-6075 3275);
PAINT MONO (-6075 3275);
DISPLAY INVISIBLE (-6075 3275);
FORCEPROP 1 LAST BODY_TYPE PLUMBING
J 0
(-6075 3325);
DISPLAY 0.872340 (-6075 3325);
PAINT GREEN (-6075 3325);
DISPLAY INVISIBLE (-6075 3325);
FORCEPROP 1 LAST HDL_TAP TRUE
J 0
(-5750 3150);
DISPLAY 0.872340 (-5750 3150);
DISPLAY INVISIBLE (-5750 3150);
FORCEPROP 1 LAST PATH I57
J 0
(-6077 3275);
DISPLAY 0.872340 (-6077 3275);
PAINT GREEN (-6077 3275);
DISPLAY INVISIBLE (-6077 3275);
FORCEADD TAP..1
(-6075 3325);
FORCEPROP 3 LASTPIN (-6125 3325) SIG_NAME M_B_CPU1_SB_DQ<20>
J 0
(-6115 3335);
DISPLAY 0.659574 (-6115 3335);
PAINT MONO (-6115 3335);
DISPLAY INVISIBLE (-6115 3335);
FORCEPROP 1 LASTPIN (-6125 3325) BN 20
J 0
(-6137 3333);
DISPLAY 0.489362 (-6137 3333);
PAINT GREEN (-6137 3333);
FORCEPROP 2 LAST CDS_LIB mstr_standard
J 0
(-6075 3325);
DISPLAY 0.723404 (-6075 3325);
PAINT MONO (-6075 3325);
DISPLAY INVISIBLE (-6075 3325);
FORCEPROP 1 LAST BODY_TYPE PLUMBING
J 0
(-6075 3375);
DISPLAY 0.872340 (-6075 3375);
PAINT GREEN (-6075 3375);
DISPLAY INVISIBLE (-6075 3375);
FORCEPROP 1 LAST HDL_TAP TRUE
J 0
(-5750 3200);
DISPLAY 0.872340 (-5750 3200);
DISPLAY INVISIBLE (-5750 3200);
FORCEPROP 1 LAST PATH I58
J 0
(-6077 3325);
DISPLAY 0.872340 (-6077 3325);
PAINT GREEN (-6077 3325);
DISPLAY INVISIBLE (-6077 3325);
FORCEADD TAP..1
(-6075 3475);
FORCEPROP 3 LASTPIN (-6125 3475) SIG_NAME M_B_CPU1_SB_DQ<23>
J 0
(-6115 3485);
DISPLAY 0.659574 (-6115 3485);
PAINT MONO (-6115 3485);
DISPLAY INVISIBLE (-6115 3485);
FORCEPROP 1 LASTPIN (-6125 3475) BN 23
J 0
(-6137 3483);
DISPLAY 0.489362 (-6137 3483);
PAINT GREEN (-6137 3483);
FORCEPROP 2 LAST CDS_LIB mstr_standard
J 0
(-6075 3475);
DISPLAY 0.723404 (-6075 3475);
PAINT MONO (-6075 3475);
DISPLAY INVISIBLE (-6075 3475);
FORCEPROP 1 LAST BODY_TYPE PLUMBING
J 0
(-6075 3525);
DISPLAY 0.872340 (-6075 3525);
PAINT GREEN (-6075 3525);
DISPLAY INVISIBLE (-6075 3525);
FORCEPROP 1 LAST HDL_TAP TRUE
J 0
(-5750 3350);
DISPLAY 0.872340 (-5750 3350);
DISPLAY INVISIBLE (-5750 3350);
FORCEPROP 1 LAST PATH I59
J 0
(-6077 3475);
DISPLAY 0.872340 (-6077 3475);
PAINT GREEN (-6077 3475);
DISPLAY INVISIBLE (-6077 3475);
FORCEADD OFFPAGE..5
(-8375 2125);
FORCEPROP 2 LAST $XR0 38 
J 0
(-8629 2125);
DISPLAY 0.638298 (-8629 2125);
PAINT MONO (-8629 2125);
FORCEPROP 2 LAST CDS_LIB mstr_standard
J 0
(-8375 2125);
DISPLAY 0.808511 (-8375 2125);
DISPLAY INVISIBLE (-8375 2125);
FORCEPROP 1 LAST OFFPAGE TRUE
J 0
(-8050 2000);
DISPLAY 0.872340 (-8050 2000);
PAINT GREEN (-8050 2000);
DISPLAY INVISIBLE (-8050 2000);
FORCEPROP 1 LAST COMMENT_BODY TRUE
J 0
(-8275 2050);
DISPLAY 0.872340 (-8275 2050);
PAINT GREEN (-8275 2050);
DISPLAY INVISIBLE (-8275 2050);
FORCEPROP 2 LAST PATH I6
J 0
(-8575 2175);
DISPLAY 1.021277 (-8575 2175);
DISPLAY INVISIBLE (-8575 2175);
FORCEADD TAP..1
(-6075 3525);
FORCEPROP 3 LASTPIN (-6125 3525) SIG_NAME M_B_CPU1_SB_DQ<24>
J 0
(-6115 3535);
DISPLAY 0.659574 (-6115 3535);
PAINT MONO (-6115 3535);
DISPLAY INVISIBLE (-6115 3535);
FORCEPROP 1 LASTPIN (-6125 3525) BN 24
J 0
(-6137 3533);
DISPLAY 0.489362 (-6137 3533);
PAINT GREEN (-6137 3533);
FORCEPROP 2 LAST CDS_LIB mstr_standard
J 0
(-6075 3525);
DISPLAY 0.723404 (-6075 3525);
PAINT MONO (-6075 3525);
DISPLAY INVISIBLE (-6075 3525);
FORCEPROP 1 LAST BODY_TYPE PLUMBING
J 0
(-6075 3575);
DISPLAY 0.872340 (-6075 3575);
PAINT GREEN (-6075 3575);
DISPLAY INVISIBLE (-6075 3575);
FORCEPROP 1 LAST HDL_TAP TRUE
J 0
(-5750 3400);
DISPLAY 0.872340 (-5750 3400);
DISPLAY INVISIBLE (-5750 3400);
FORCEPROP 1 LAST PATH I60
J 0
(-6077 3525);
DISPLAY 0.872340 (-6077 3525);
PAINT GREEN (-6077 3525);
DISPLAY INVISIBLE (-6077 3525);
FORCEADD TAP..1
(-6075 3575);
FORCEPROP 3 LASTPIN (-6125 3575) SIG_NAME M_B_CPU1_SB_DQ<25>
J 0
(-6115 3585);
DISPLAY 0.659574 (-6115 3585);
PAINT MONO (-6115 3585);
DISPLAY INVISIBLE (-6115 3585);
FORCEPROP 1 LASTPIN (-6125 3575) BN 25
J 0
(-6137 3583);
DISPLAY 0.489362 (-6137 3583);
PAINT GREEN (-6137 3583);
FORCEPROP 2 LAST CDS_LIB mstr_standard
J 0
(-6075 3575);
DISPLAY 0.723404 (-6075 3575);
PAINT MONO (-6075 3575);
DISPLAY INVISIBLE (-6075 3575);
FORCEPROP 1 LAST BODY_TYPE PLUMBING
J 0
(-6075 3625);
DISPLAY 0.872340 (-6075 3625);
PAINT GREEN (-6075 3625);
DISPLAY INVISIBLE (-6075 3625);
FORCEPROP 1 LAST HDL_TAP TRUE
J 0
(-5750 3450);
DISPLAY 0.872340 (-5750 3450);
DISPLAY INVISIBLE (-5750 3450);
FORCEPROP 1 LAST PATH I61
J 0
(-6077 3575);
DISPLAY 0.872340 (-6077 3575);
PAINT GREEN (-6077 3575);
DISPLAY INVISIBLE (-6077 3575);
FORCEADD TAP..1
(-6075 3425);
FORCEPROP 3 LASTPIN (-6125 3425) SIG_NAME M_B_CPU1_SB_DQ<22>
J 0
(-6115 3435);
DISPLAY 0.659574 (-6115 3435);
PAINT MONO (-6115 3435);
DISPLAY INVISIBLE (-6115 3435);
FORCEPROP 1 LASTPIN (-6125 3425) BN 22
J 0
(-6137 3433);
DISPLAY 0.489362 (-6137 3433);
PAINT GREEN (-6137 3433);
FORCEPROP 2 LAST CDS_LIB mstr_standard
J 0
(-6075 3425);
DISPLAY 0.723404 (-6075 3425);
PAINT MONO (-6075 3425);
DISPLAY INVISIBLE (-6075 3425);
FORCEPROP 1 LAST BODY_TYPE PLUMBING
J 0
(-6075 3475);
DISPLAY 0.872340 (-6075 3475);
PAINT GREEN (-6075 3475);
DISPLAY INVISIBLE (-6075 3475);
FORCEPROP 1 LAST HDL_TAP TRUE
J 0
(-5750 3300);
DISPLAY 0.872340 (-5750 3300);
DISPLAY INVISIBLE (-5750 3300);
FORCEPROP 1 LAST PATH I62
J 0
(-6077 3425);
DISPLAY 0.872340 (-6077 3425);
PAINT GREEN (-6077 3425);
DISPLAY INVISIBLE (-6077 3425);
FORCEADD TAP..1
(-6075 3375);
FORCEPROP 3 LASTPIN (-6125 3375) SIG_NAME M_B_CPU1_SB_DQ<21>
J 0
(-6115 3385);
DISPLAY 0.659574 (-6115 3385);
PAINT MONO (-6115 3385);
DISPLAY INVISIBLE (-6115 3385);
FORCEPROP 1 LASTPIN (-6125 3375) BN 21
J 0
(-6137 3383);
DISPLAY 0.489362 (-6137 3383);
PAINT GREEN (-6137 3383);
FORCEPROP 2 LAST CDS_LIB mstr_standard
J 0
(-6075 3375);
DISPLAY 0.723404 (-6075 3375);
PAINT MONO (-6075 3375);
DISPLAY INVISIBLE (-6075 3375);
FORCEPROP 1 LAST BODY_TYPE PLUMBING
J 0
(-6075 3425);
DISPLAY 0.872340 (-6075 3425);
PAINT GREEN (-6075 3425);
DISPLAY INVISIBLE (-6075 3425);
FORCEPROP 1 LAST HDL_TAP TRUE
J 0
(-5750 3250);
DISPLAY 0.872340 (-5750 3250);
DISPLAY INVISIBLE (-5750 3250);
FORCEPROP 1 LAST PATH I63
J 0
(-6077 3375);
DISPLAY 0.872340 (-6077 3375);
PAINT GREEN (-6077 3375);
DISPLAY INVISIBLE (-6077 3375);
FORCEADD TAP..1
(-6075 3725);
FORCEPROP 3 LASTPIN (-6125 3725) SIG_NAME M_B_CPU1_SB_DQ<28>
J 0
(-6115 3735);
DISPLAY 0.659574 (-6115 3735);
PAINT MONO (-6115 3735);
DISPLAY INVISIBLE (-6115 3735);
FORCEPROP 1 LASTPIN (-6125 3725) BN 28
J 0
(-6137 3733);
DISPLAY 0.489362 (-6137 3733);
PAINT GREEN (-6137 3733);
FORCEPROP 2 LAST CDS_LIB mstr_standard
J 0
(-6075 3725);
DISPLAY 0.723404 (-6075 3725);
PAINT MONO (-6075 3725);
DISPLAY INVISIBLE (-6075 3725);
FORCEPROP 1 LAST BODY_TYPE PLUMBING
J 0
(-6075 3775);
DISPLAY 0.872340 (-6075 3775);
PAINT GREEN (-6075 3775);
DISPLAY INVISIBLE (-6075 3775);
FORCEPROP 1 LAST HDL_TAP TRUE
J 0
(-5750 3600);
DISPLAY 0.872340 (-5750 3600);
DISPLAY INVISIBLE (-5750 3600);
FORCEPROP 1 LAST PATH I64
J 0
(-6077 3725);
DISPLAY 0.872340 (-6077 3725);
PAINT GREEN (-6077 3725);
DISPLAY INVISIBLE (-6077 3725);
FORCEADD TAP..1
(-6075 3825);
FORCEPROP 3 LASTPIN (-6125 3825) SIG_NAME M_B_CPU1_SB_DQ<30>
J 0
(-6115 3835);
DISPLAY 0.659574 (-6115 3835);
PAINT MONO (-6115 3835);
DISPLAY INVISIBLE (-6115 3835);
FORCEPROP 1 LASTPIN (-6125 3825) BN 30
J 0
(-6137 3833);
DISPLAY 0.489362 (-6137 3833);
PAINT GREEN (-6137 3833);
FORCEPROP 2 LAST CDS_LIB mstr_standard
J 0
(-6075 3825);
DISPLAY 0.723404 (-6075 3825);
PAINT MONO (-6075 3825);
DISPLAY INVISIBLE (-6075 3825);
FORCEPROP 1 LAST BODY_TYPE PLUMBING
J 0
(-6075 3875);
DISPLAY 0.872340 (-6075 3875);
PAINT GREEN (-6075 3875);
DISPLAY INVISIBLE (-6075 3875);
FORCEPROP 1 LAST HDL_TAP TRUE
J 0
(-5750 3700);
DISPLAY 0.872340 (-5750 3700);
DISPLAY INVISIBLE (-5750 3700);
FORCEPROP 1 LAST PATH I65
J 0
(-6077 3825);
DISPLAY 0.872340 (-6077 3825);
PAINT GREEN (-6077 3825);
DISPLAY INVISIBLE (-6077 3825);
FORCEADD TAP..1
(-6075 3775);
FORCEPROP 3 LASTPIN (-6125 3775) SIG_NAME M_B_CPU1_SB_DQ<29>
J 0
(-6115 3785);
DISPLAY 0.659574 (-6115 3785);
PAINT MONO (-6115 3785);
DISPLAY INVISIBLE (-6115 3785);
FORCEPROP 1 LASTPIN (-6125 3775) BN 29
J 0
(-6137 3783);
DISPLAY 0.489362 (-6137 3783);
PAINT GREEN (-6137 3783);
FORCEPROP 2 LAST CDS_LIB mstr_standard
J 0
(-6075 3775);
DISPLAY 0.723404 (-6075 3775);
PAINT MONO (-6075 3775);
DISPLAY INVISIBLE (-6075 3775);
FORCEPROP 1 LAST BODY_TYPE PLUMBING
J 0
(-6075 3825);
DISPLAY 0.872340 (-6075 3825);
PAINT GREEN (-6075 3825);
DISPLAY INVISIBLE (-6075 3825);
FORCEPROP 1 LAST HDL_TAP TRUE
J 0
(-5750 3650);
DISPLAY 0.872340 (-5750 3650);
DISPLAY INVISIBLE (-5750 3650);
FORCEPROP 1 LAST PATH I66
J 0
(-6077 3775);
DISPLAY 0.872340 (-6077 3775);
PAINT GREEN (-6077 3775);
DISPLAY INVISIBLE (-6077 3775);
FORCEADD TAP..1
(-6075 3675);
FORCEPROP 3 LASTPIN (-6125 3675) SIG_NAME M_B_CPU1_SB_DQ<27>
J 0
(-6115 3685);
DISPLAY 0.659574 (-6115 3685);
PAINT MONO (-6115 3685);
DISPLAY INVISIBLE (-6115 3685);
FORCEPROP 1 LASTPIN (-6125 3675) BN 27
J 0
(-6137 3683);
DISPLAY 0.489362 (-6137 3683);
PAINT GREEN (-6137 3683);
FORCEPROP 2 LAST CDS_LIB mstr_standard
J 0
(-6075 3675);
DISPLAY 0.723404 (-6075 3675);
PAINT MONO (-6075 3675);
DISPLAY INVISIBLE (-6075 3675);
FORCEPROP 1 LAST BODY_TYPE PLUMBING
J 0
(-6075 3725);
DISPLAY 0.872340 (-6075 3725);
PAINT GREEN (-6075 3725);
DISPLAY INVISIBLE (-6075 3725);
FORCEPROP 1 LAST HDL_TAP TRUE
J 0
(-5750 3550);
DISPLAY 0.872340 (-5750 3550);
DISPLAY INVISIBLE (-5750 3550);
FORCEPROP 1 LAST PATH I67
J 0
(-6077 3675);
DISPLAY 0.872340 (-6077 3675);
PAINT GREEN (-6077 3675);
DISPLAY INVISIBLE (-6077 3675);
FORCEADD TAP..1
(-6075 3625);
FORCEPROP 3 LASTPIN (-6125 3625) SIG_NAME M_B_CPU1_SB_DQ<26>
J 0
(-6115 3635);
DISPLAY 0.659574 (-6115 3635);
PAINT MONO (-6115 3635);
DISPLAY INVISIBLE (-6115 3635);
FORCEPROP 1 LASTPIN (-6125 3625) BN 26
J 0
(-6137 3633);
DISPLAY 0.489362 (-6137 3633);
PAINT GREEN (-6137 3633);
FORCEPROP 2 LAST CDS_LIB mstr_standard
J 0
(-6075 3625);
DISPLAY 0.723404 (-6075 3625);
PAINT MONO (-6075 3625);
DISPLAY INVISIBLE (-6075 3625);
FORCEPROP 1 LAST BODY_TYPE PLUMBING
J 0
(-6075 3675);
DISPLAY 0.872340 (-6075 3675);
PAINT GREEN (-6075 3675);
DISPLAY INVISIBLE (-6075 3675);
FORCEPROP 1 LAST HDL_TAP TRUE
J 0
(-5750 3500);
DISPLAY 0.872340 (-5750 3500);
DISPLAY INVISIBLE (-5750 3500);
FORCEPROP 1 LAST PATH I68
J 0
(-6077 3625);
DISPLAY 0.872340 (-6077 3625);
PAINT GREEN (-6077 3625);
DISPLAY INVISIBLE (-6077 3625);
FORCEADD TAP..1
(-6075 3875);
FORCEPROP 3 LASTPIN (-6125 3875) SIG_NAME M_B_CPU1_SB_DQ<31>
J 0
(-6115 3885);
DISPLAY 0.659574 (-6115 3885);
PAINT MONO (-6115 3885);
DISPLAY INVISIBLE (-6115 3885);
FORCEPROP 1 LASTPIN (-6125 3875) BN 31
J 0
(-6137 3883);
DISPLAY 0.489362 (-6137 3883);
PAINT GREEN (-6137 3883);
FORCEPROP 2 LAST CDS_LIB mstr_standard
J 0
(-6075 3875);
DISPLAY 0.723404 (-6075 3875);
PAINT MONO (-6075 3875);
DISPLAY INVISIBLE (-6075 3875);
FORCEPROP 1 LAST BODY_TYPE PLUMBING
J 0
(-6075 3925);
DISPLAY 0.872340 (-6075 3925);
PAINT GREEN (-6075 3925);
DISPLAY INVISIBLE (-6075 3925);
FORCEPROP 1 LAST HDL_TAP TRUE
J 0
(-5750 3750);
DISPLAY 0.872340 (-5750 3750);
DISPLAY INVISIBLE (-5750 3750);
FORCEPROP 1 LAST PATH I69
J 0
(-6077 3875);
DISPLAY 0.872340 (-6077 3875);
PAINT GREEN (-6077 3875);
DISPLAY INVISIBLE (-6077 3875);
FORCEADD VCC_CORE..1
(-8625 3550);
FORCEPROP 3 LASTPIN (-8625 3500) SIG_NAME P3V3_AUX\g
J 0
(-8615 3510);
DISPLAY 0.659574 (-8615 3510);
PAINT MONO (-8615 3510);
DISPLAY INVISIBLE (-8615 3510);
FORCEPROP 1 LAST HDL_POWER P3V3_AUX
J 1
(-8625 3600);
DISPLAY 0.489362 (-8625 3600);
PAINT GREEN (-8625 3600);
FORCEPROP 2 LAST CDS_LIB mstr_symbols
J 0
(-8625 3550);
PAINT MONO (-8625 3550);
DISPLAY INVISIBLE (-8625 3550);
FORCEPROP 0 LAST VOLTAGE 3.3
J 0
(-8900 3700);
DISPLAY 1.021277 (-8900 3700);
PAINT SKYBLUE (-8900 3700);
DISPLAY INVISIBLE (-8900 3700);
FORCEPROP 2 LAST ROOM PVCCINFAON_CPU1_CTRL
J 0
(-8625 3650);
DISPLAY 0.808511 (-8625 3650);
PAINT RED (-8625 3650);
DISPLAY INVISIBLE (-8625 3650);
FORCEPROP 1 LAST PATH I7
J 0
(-8575 3575);
DISPLAY 0.872340 (-8575 3575);
PAINT AQUA (-8575 3575);
DISPLAY INVISIBLE (-8575 3575);
FORCEADD TAP..1
(-6075 4025);
FORCEPROP 3 LASTPIN (-6125 4025) SIG_NAME M_B_CPU1_SA_DQ<1>
J 0
(-6115 4035);
DISPLAY 0.659574 (-6115 4035);
PAINT MONO (-6115 4035);
DISPLAY INVISIBLE (-6115 4035);
FORCEPROP 1 LASTPIN (-6125 4025) BN 1
J 0
(-6137 4033);
DISPLAY 0.489362 (-6137 4033);
PAINT GREEN (-6137 4033);
FORCEPROP 2 LAST CDS_LIB mstr_standard
J 0
(-6075 4025);
DISPLAY 0.723404 (-6075 4025);
PAINT MONO (-6075 4025);
DISPLAY INVISIBLE (-6075 4025);
FORCEPROP 1 LAST BODY_TYPE PLUMBING
J 0
(-6075 4075);
DISPLAY 0.872340 (-6075 4075);
PAINT GREEN (-6075 4075);
DISPLAY INVISIBLE (-6075 4075);
FORCEPROP 1 LAST HDL_TAP TRUE
J 0
(-5750 3900);
DISPLAY 0.872340 (-5750 3900);
DISPLAY INVISIBLE (-5750 3900);
FORCEPROP 1 LAST PATH I70
J 0
(-6077 4025);
DISPLAY 0.872340 (-6077 4025);
PAINT GREEN (-6077 4025);
DISPLAY INVISIBLE (-6077 4025);
FORCEADD TAP..1
(-6075 4075);
FORCEPROP 3 LASTPIN (-6125 4075) SIG_NAME M_B_CPU1_SA_DQ<2>
J 0
(-6115 4085);
DISPLAY 0.659574 (-6115 4085);
PAINT MONO (-6115 4085);
DISPLAY INVISIBLE (-6115 4085);
FORCEPROP 1 LASTPIN (-6125 4075) BN 2
J 0
(-6137 4083);
DISPLAY 0.489362 (-6137 4083);
PAINT GREEN (-6137 4083);
FORCEPROP 2 LAST CDS_LIB mstr_standard
J 0
(-6075 4075);
DISPLAY 0.723404 (-6075 4075);
PAINT MONO (-6075 4075);
DISPLAY INVISIBLE (-6075 4075);
FORCEPROP 1 LAST BODY_TYPE PLUMBING
J 0
(-6075 4125);
DISPLAY 0.872340 (-6075 4125);
PAINT GREEN (-6075 4125);
DISPLAY INVISIBLE (-6075 4125);
FORCEPROP 1 LAST HDL_TAP TRUE
J 0
(-5750 3950);
DISPLAY 0.872340 (-5750 3950);
DISPLAY INVISIBLE (-5750 3950);
FORCEPROP 1 LAST PATH I71
J 0
(-6077 4075);
DISPLAY 0.872340 (-6077 4075);
PAINT GREEN (-6077 4075);
DISPLAY INVISIBLE (-6077 4075);
FORCEADD TAP..1
(-6075 3975);
FORCEPROP 3 LASTPIN (-6125 3975) SIG_NAME M_B_CPU1_SA_DQ<0>
J 0
(-6115 3985);
DISPLAY 0.659574 (-6115 3985);
PAINT MONO (-6115 3985);
DISPLAY INVISIBLE (-6115 3985);
FORCEPROP 1 LASTPIN (-6125 3975) BN 0
J 0
(-6137 3983);
DISPLAY 0.489362 (-6137 3983);
PAINT GREEN (-6137 3983);
FORCEPROP 2 LAST CDS_LIB mstr_standard
J 0
(-6075 3975);
DISPLAY 0.723404 (-6075 3975);
PAINT MONO (-6075 3975);
DISPLAY INVISIBLE (-6075 3975);
FORCEPROP 1 LAST BODY_TYPE PLUMBING
J 0
(-6075 4025);
DISPLAY 0.872340 (-6075 4025);
PAINT GREEN (-6075 4025);
DISPLAY INVISIBLE (-6075 4025);
FORCEPROP 1 LAST HDL_TAP TRUE
J 0
(-5750 3850);
DISPLAY 0.872340 (-5750 3850);
DISPLAY INVISIBLE (-5750 3850);
FORCEPROP 1 LAST PATH I72
J 0
(-6077 3975);
DISPLAY 0.872340 (-6077 3975);
PAINT GREEN (-6077 3975);
DISPLAY INVISIBLE (-6077 3975);
FORCEADD OFFPAGE..3
(-5325 3925);
FORCEPROP 2 LAST $XR0 38 
J 0
(-5111 3925);
DISPLAY 0.638298 (-5111 3925);
PAINT MONO (-5111 3925);
FORCEPROP 2 LAST CDS_LIB mstr_standard
J 0
(-5325 3925);
DISPLAY 0.723404 (-5325 3925);
PAINT MONO (-5325 3925);
DISPLAY INVISIBLE (-5325 3925);
FORCEPROP 1 LAST OFFPAGE TRUE
J 0
(-5000 3800);
DISPLAY 0.872340 (-5000 3800);
PAINT GREEN (-5000 3800);
DISPLAY INVISIBLE (-5000 3800);
FORCEPROP 1 LAST COMMENT_BODY TRUE
J 0
(-5375 3825);
DISPLAY 0.872340 (-5375 3825);
PAINT GREEN (-5375 3825);
DISPLAY INVISIBLE (-5375 3825);
FORCEPROP 2 LAST PATH I79
J 0
(-5100 3975);
DISPLAY 1.021277 (-5100 3975);
DISPLAY INVISIBLE (-5100 3975);
FORCEADD OFFPAGE..6
(-8375 3725);
FORCEPROP 2 LAST $XR0 38 
J 0
(-8654 3725);
DISPLAY 0.638298 (-8654 3725);
PAINT MONO (-8654 3725);
FORCEPROP 2 LAST CDS_LIB mstr_standard
J 0
(-8375 3725);
DISPLAY 0.723404 (-8375 3725);
PAINT MONO (-8375 3725);
DISPLAY INVISIBLE (-8375 3725);
FORCEPROP 1 LAST OFFPAGE TRUE
J 0
(-8050 3600);
DISPLAY 0.872340 (-8050 3600);
PAINT GREEN (-8050 3600);
DISPLAY INVISIBLE (-8050 3600);
FORCEPROP 1 LAST COMMENT_BODY TRUE
J 0
(-8275 3650);
DISPLAY 0.872340 (-8275 3650);
PAINT GREEN (-8275 3650);
DISPLAY INVISIBLE (-8275 3650);
FORCEPROP 2 LAST PATH I8
J 0
(-8600 3775);
DISPLAY 1.021277 (-8600 3775);
DISPLAY INVISIBLE (-8600 3775);
FORCEADD TAP..1
R 2
(-7775 4125);
FORCEPROP 3 LASTPIN (-7725 4125) SIG_NAME M_B_CPU1_SA_CB<7>
J 0
(-7715 4135);
DISPLAY 0.659574 (-7715 4135);
PAINT MONO (-7715 4135);
DISPLAY INVISIBLE (-7715 4135);
FORCEPROP 1 LASTPIN (-7725 4125) BN 7
J 2
(-7713 4133);
DISPLAY 0.489362 (-7713 4133);
PAINT GREEN (-7713 4133);
FORCEPROP 2 LAST CDS_LIB mstr_standard
J 0
(-7775 4125);
DISPLAY 0.723404 (-7775 4125);
PAINT MONO (-7775 4125);
DISPLAY INVISIBLE (-7775 4125);
FORCEPROP 1 LAST BODY_TYPE PLUMBING
J 2
(-7775 4175);
DISPLAY 0.872340 (-7775 4175);
PAINT GREEN (-7775 4175);
DISPLAY INVISIBLE (-7775 4175);
FORCEPROP 1 LAST HDL_TAP TRUE
J 2
(-8100 4000);
DISPLAY 0.872340 (-8100 4000);
DISPLAY INVISIBLE (-8100 4000);
FORCEPROP 1 LAST PATH I81
J 2
(-7773 4125);
DISPLAY 0.872340 (-7773 4125);
PAINT GREEN (-7773 4125);
DISPLAY INVISIBLE (-7773 4125);
FORCEADD TAP..1
R 2
(-7775 4825);
FORCEPROP 3 LASTPIN (-7725 4825) SIG_NAME M_B_CPU1_SB_CA<0>
J 0
(-7715 4835);
DISPLAY 0.659574 (-7715 4835);
PAINT MONO (-7715 4835);
DISPLAY INVISIBLE (-7715 4835);
FORCEPROP 1 LASTPIN (-7725 4825) BN 0
J 2
(-7713 4833);
DISPLAY 0.489362 (-7713 4833);
PAINT GREEN (-7713 4833);
FORCEPROP 2 LAST CDS_LIB mstr_standard
J 0
(-7775 4825);
DISPLAY 0.723404 (-7775 4825);
PAINT MONO (-7775 4825);
DISPLAY INVISIBLE (-7775 4825);
FORCEPROP 1 LAST BODY_TYPE PLUMBING
J 2
(-7775 4875);
DISPLAY 0.872340 (-7775 4875);
PAINT GREEN (-7775 4875);
DISPLAY INVISIBLE (-7775 4875);
FORCEPROP 1 LAST HDL_TAP TRUE
J 2
(-8100 4700);
DISPLAY 0.872340 (-8100 4700);
DISPLAY INVISIBLE (-8100 4700);
FORCEPROP 1 LAST PATH I82
J 2
(-7773 4825);
DISPLAY 0.872340 (-7773 4825);
PAINT GREEN (-7773 4825);
DISPLAY INVISIBLE (-7773 4825);
FORCEADD TAP..1
R 2
(-7775 4875);
FORCEPROP 3 LASTPIN (-7725 4875) SIG_NAME M_B_CPU1_SB_CA<1>
J 0
(-7715 4885);
DISPLAY 0.659574 (-7715 4885);
PAINT MONO (-7715 4885);
DISPLAY INVISIBLE (-7715 4885);
FORCEPROP 1 LASTPIN (-7725 4875) BN 1
J 2
(-7713 4883);
DISPLAY 0.489362 (-7713 4883);
PAINT GREEN (-7713 4883);
FORCEPROP 2 LAST CDS_LIB mstr_standard
J 0
(-7775 4875);
DISPLAY 0.723404 (-7775 4875);
PAINT MONO (-7775 4875);
DISPLAY INVISIBLE (-7775 4875);
FORCEPROP 1 LAST BODY_TYPE PLUMBING
J 2
(-7775 4925);
DISPLAY 0.872340 (-7775 4925);
PAINT GREEN (-7775 4925);
DISPLAY INVISIBLE (-7775 4925);
FORCEPROP 1 LAST HDL_TAP TRUE
J 2
(-8100 4750);
DISPLAY 0.872340 (-8100 4750);
DISPLAY INVISIBLE (-8100 4750);
FORCEPROP 1 LAST PATH I83
J 2
(-7773 4875);
DISPLAY 0.872340 (-7773 4875);
PAINT GREEN (-7773 4875);
DISPLAY INVISIBLE (-7773 4875);
FORCEADD TAP..1
R 2
(-7775 4925);
FORCEPROP 3 LASTPIN (-7725 4925) SIG_NAME M_B_CPU1_SB_CA<2>
J 0
(-7715 4935);
DISPLAY 0.659574 (-7715 4935);
PAINT MONO (-7715 4935);
DISPLAY INVISIBLE (-7715 4935);
FORCEPROP 1 LASTPIN (-7725 4925) BN 2
J 2
(-7713 4933);
DISPLAY 0.489362 (-7713 4933);
PAINT GREEN (-7713 4933);
FORCEPROP 2 LAST CDS_LIB mstr_standard
J 0
(-7775 4925);
DISPLAY 0.723404 (-7775 4925);
PAINT MONO (-7775 4925);
DISPLAY INVISIBLE (-7775 4925);
FORCEPROP 1 LAST BODY_TYPE PLUMBING
J 2
(-7775 4975);
DISPLAY 0.872340 (-7775 4975);
PAINT GREEN (-7775 4975);
DISPLAY INVISIBLE (-7775 4975);
FORCEPROP 1 LAST HDL_TAP TRUE
J 2
(-8100 4800);
DISPLAY 0.872340 (-8100 4800);
DISPLAY INVISIBLE (-8100 4800);
FORCEPROP 1 LAST PATH I84
J 2
(-7773 4925);
DISPLAY 0.872340 (-7773 4925);
PAINT GREEN (-7773 4925);
DISPLAY INVISIBLE (-7773 4925);
FORCEADD TAP..1
R 2
(-7775 4975);
FORCEPROP 3 LASTPIN (-7725 4975) SIG_NAME M_B_CPU1_SB_CA<3>
J 0
(-7715 4985);
DISPLAY 0.659574 (-7715 4985);
PAINT MONO (-7715 4985);
DISPLAY INVISIBLE (-7715 4985);
FORCEPROP 1 LASTPIN (-7725 4975) BN 3
J 2
(-7713 4983);
DISPLAY 0.489362 (-7713 4983);
PAINT GREEN (-7713 4983);
FORCEPROP 2 LAST CDS_LIB mstr_standard
J 0
(-7775 4975);
DISPLAY 0.723404 (-7775 4975);
PAINT MONO (-7775 4975);
DISPLAY INVISIBLE (-7775 4975);
FORCEPROP 1 LAST BODY_TYPE PLUMBING
J 2
(-7775 5025);
DISPLAY 0.872340 (-7775 5025);
PAINT GREEN (-7775 5025);
DISPLAY INVISIBLE (-7775 5025);
FORCEPROP 1 LAST HDL_TAP TRUE
J 2
(-8100 4850);
DISPLAY 0.872340 (-8100 4850);
DISPLAY INVISIBLE (-8100 4850);
FORCEPROP 1 LAST PATH I85
J 2
(-7773 4975);
DISPLAY 0.872340 (-7773 4975);
PAINT GREEN (-7773 4975);
DISPLAY INVISIBLE (-7773 4975);
FORCEADD TAP..1
R 2
(-7775 5075);
FORCEPROP 3 LASTPIN (-7725 5075) SIG_NAME M_B_CPU1_SB_CA<5>
J 0
(-7715 5085);
DISPLAY 0.659574 (-7715 5085);
PAINT MONO (-7715 5085);
DISPLAY INVISIBLE (-7715 5085);
FORCEPROP 1 LASTPIN (-7725 5075) BN 5
J 2
(-7713 5083);
DISPLAY 0.489362 (-7713 5083);
PAINT GREEN (-7713 5083);
FORCEPROP 2 LAST CDS_LIB mstr_standard
J 0
(-7775 5075);
DISPLAY 0.723404 (-7775 5075);
PAINT MONO (-7775 5075);
DISPLAY INVISIBLE (-7775 5075);
FORCEPROP 1 LAST BODY_TYPE PLUMBING
J 2
(-7775 5125);
DISPLAY 0.872340 (-7775 5125);
PAINT GREEN (-7775 5125);
DISPLAY INVISIBLE (-7775 5125);
FORCEPROP 1 LAST HDL_TAP TRUE
J 2
(-8100 4950);
DISPLAY 0.872340 (-8100 4950);
DISPLAY INVISIBLE (-8100 4950);
FORCEPROP 1 LAST PATH I86
J 2
(-7773 5075);
DISPLAY 0.872340 (-7773 5075);
PAINT GREEN (-7773 5075);
DISPLAY INVISIBLE (-7773 5075);
FORCEADD TAP..1
R 2
(-7775 5025);
FORCEPROP 3 LASTPIN (-7725 5025) SIG_NAME M_B_CPU1_SB_CA<4>
J 0
(-7715 5035);
DISPLAY 0.659574 (-7715 5035);
PAINT MONO (-7715 5035);
DISPLAY INVISIBLE (-7715 5035);
FORCEPROP 1 LASTPIN (-7725 5025) BN 4
J 2
(-7713 5033);
DISPLAY 0.489362 (-7713 5033);
PAINT GREEN (-7713 5033);
FORCEPROP 2 LAST CDS_LIB mstr_standard
J 0
(-7775 5025);
DISPLAY 0.723404 (-7775 5025);
PAINT MONO (-7775 5025);
DISPLAY INVISIBLE (-7775 5025);
FORCEPROP 1 LAST BODY_TYPE PLUMBING
J 2
(-7775 5075);
DISPLAY 0.872340 (-7775 5075);
PAINT GREEN (-7775 5075);
DISPLAY INVISIBLE (-7775 5075);
FORCEPROP 1 LAST HDL_TAP TRUE
J 2
(-8100 4900);
DISPLAY 0.872340 (-8100 4900);
DISPLAY INVISIBLE (-8100 4900);
FORCEPROP 1 LAST PATH I87
J 2
(-7773 5025);
DISPLAY 0.872340 (-7773 5025);
PAINT GREEN (-7773 5025);
DISPLAY INVISIBLE (-7773 5025);
FORCEADD TAP..1
R 2
(-7775 5225);
FORCEPROP 3 LASTPIN (-7725 5225) SIG_NAME M_B_CPU1_SA_CA<0>
J 0
(-7715 5235);
DISPLAY 0.659574 (-7715 5235);
PAINT MONO (-7715 5235);
DISPLAY INVISIBLE (-7715 5235);
FORCEPROP 1 LASTPIN (-7725 5225) BN 0
J 2
(-7713 5233);
DISPLAY 0.489362 (-7713 5233);
PAINT GREEN (-7713 5233);
FORCEPROP 2 LAST CDS_LIB mstr_standard
J 0
(-7775 5225);
DISPLAY 0.723404 (-7775 5225);
PAINT MONO (-7775 5225);
DISPLAY INVISIBLE (-7775 5225);
FORCEPROP 1 LAST BODY_TYPE PLUMBING
J 2
(-7775 5275);
DISPLAY 0.872340 (-7775 5275);
PAINT GREEN (-7775 5275);
DISPLAY INVISIBLE (-7775 5275);
FORCEPROP 1 LAST HDL_TAP TRUE
J 2
(-8100 5100);
DISPLAY 0.872340 (-8100 5100);
DISPLAY INVISIBLE (-8100 5100);
FORCEPROP 1 LAST PATH I88
J 2
(-7773 5225);
DISPLAY 0.872340 (-7773 5225);
PAINT GREEN (-7773 5225);
DISPLAY INVISIBLE (-7773 5225);
FORCEADD TAP..1
R 2
(-7775 5125);
FORCEPROP 3 LASTPIN (-7725 5125) SIG_NAME M_B_CPU1_SB_CA<6>
J 0
(-7715 5135);
DISPLAY 0.659574 (-7715 5135);
PAINT MONO (-7715 5135);
DISPLAY INVISIBLE (-7715 5135);
FORCEPROP 1 LASTPIN (-7725 5125) BN 6
J 2
(-7713 5133);
DISPLAY 0.489362 (-7713 5133);
PAINT GREEN (-7713 5133);
FORCEPROP 2 LAST CDS_LIB mstr_standard
J 0
(-7775 5125);
DISPLAY 0.723404 (-7775 5125);
PAINT MONO (-7775 5125);
DISPLAY INVISIBLE (-7775 5125);
FORCEPROP 1 LAST BODY_TYPE PLUMBING
J 2
(-7775 5175);
DISPLAY 0.872340 (-7775 5175);
PAINT GREEN (-7775 5175);
DISPLAY INVISIBLE (-7775 5175);
FORCEPROP 1 LAST HDL_TAP TRUE
J 2
(-8100 5000);
DISPLAY 0.872340 (-8100 5000);
DISPLAY INVISIBLE (-8100 5000);
FORCEPROP 1 LAST PATH I89
J 2
(-7773 5125);
DISPLAY 0.872340 (-7773 5125);
PAINT GREEN (-7773 5125);
DISPLAY INVISIBLE (-7773 5125);
FORCEADD OFFPAGE..5
(-8200 3175);
FORCEPROP 2 LAST $XR0 38 
J 0
(-8424 3175);
DISPLAY 0.638298 (-8424 3175);
PAINT MONO (-8424 3175);
FORCEPROP 2 LAST CDS_LIB mstr_standard
J 0
(-8200 3175);
DISPLAY INVISIBLE (-8200 3175);
FORCEPROP 1 LAST OFFPAGE TRUE
J 0
(-7875 3050);
DISPLAY 0.872340 (-7875 3050);
PAINT GREEN (-7875 3050);
DISPLAY INVISIBLE (-7875 3050);
FORCEPROP 1 LAST COMMENT_BODY TRUE
J 0
(-8100 3100);
DISPLAY 0.872340 (-8100 3100);
PAINT GREEN (-8100 3100);
DISPLAY INVISIBLE (-8100 3100);
FORCEPROP 2 LAST PATH I9
J 0
(-8450 3225);
DISPLAY 1.021277 (-8450 3225);
DISPLAY INVISIBLE (-8450 3225);
FORCEADD TAP..1
R 2
(-7775 5275);
FORCEPROP 3 LASTPIN (-7725 5275) SIG_NAME M_B_CPU1_SA_CA<1>
J 0
(-7715 5285);
DISPLAY 0.659574 (-7715 5285);
PAINT MONO (-7715 5285);
DISPLAY INVISIBLE (-7715 5285);
FORCEPROP 1 LASTPIN (-7725 5275) BN 1
J 2
(-7713 5283);
DISPLAY 0.489362 (-7713 5283);
PAINT GREEN (-7713 5283);
FORCEPROP 2 LAST CDS_LIB mstr_standard
J 0
(-7775 5275);
DISPLAY 0.723404 (-7775 5275);
PAINT MONO (-7775 5275);
DISPLAY INVISIBLE (-7775 5275);
FORCEPROP 1 LAST BODY_TYPE PLUMBING
J 2
(-7775 5325);
DISPLAY 0.872340 (-7775 5325);
PAINT GREEN (-7775 5325);
DISPLAY INVISIBLE (-7775 5325);
FORCEPROP 1 LAST HDL_TAP TRUE
J 2
(-8100 5150);
DISPLAY 0.872340 (-8100 5150);
DISPLAY INVISIBLE (-8100 5150);
FORCEPROP 1 LAST PATH I90
J 2
(-7773 5275);
DISPLAY 0.872340 (-7773 5275);
PAINT GREEN (-7773 5275);
DISPLAY INVISIBLE (-7773 5275);
FORCEADD TAP..1
R 2
(-7775 5325);
FORCEPROP 3 LASTPIN (-7725 5325) SIG_NAME M_B_CPU1_SA_CA<2>
J 0
(-7715 5335);
DISPLAY 0.659574 (-7715 5335);
PAINT MONO (-7715 5335);
DISPLAY INVISIBLE (-7715 5335);
FORCEPROP 1 LASTPIN (-7725 5325) BN 2
J 2
(-7713 5333);
DISPLAY 0.489362 (-7713 5333);
PAINT GREEN (-7713 5333);
FORCEPROP 2 LAST CDS_LIB mstr_standard
J 0
(-7775 5325);
DISPLAY 0.723404 (-7775 5325);
PAINT MONO (-7775 5325);
DISPLAY INVISIBLE (-7775 5325);
FORCEPROP 1 LAST BODY_TYPE PLUMBING
J 2
(-7775 5375);
DISPLAY 0.872340 (-7775 5375);
PAINT GREEN (-7775 5375);
DISPLAY INVISIBLE (-7775 5375);
FORCEPROP 1 LAST HDL_TAP TRUE
J 2
(-8100 5200);
DISPLAY 0.872340 (-8100 5200);
DISPLAY INVISIBLE (-8100 5200);
FORCEPROP 1 LAST PATH I91
J 2
(-7773 5325);
DISPLAY 0.872340 (-7773 5325);
PAINT GREEN (-7773 5325);
DISPLAY INVISIBLE (-7773 5325);
FORCEADD TAP..1
R 2
(-7775 5375);
FORCEPROP 3 LASTPIN (-7725 5375) SIG_NAME M_B_CPU1_SA_CA<3>
J 0
(-7715 5385);
DISPLAY 0.659574 (-7715 5385);
PAINT MONO (-7715 5385);
DISPLAY INVISIBLE (-7715 5385);
FORCEPROP 1 LASTPIN (-7725 5375) BN 3
J 2
(-7713 5383);
DISPLAY 0.489362 (-7713 5383);
PAINT GREEN (-7713 5383);
FORCEPROP 2 LAST CDS_LIB mstr_standard
J 0
(-7775 5375);
DISPLAY 0.723404 (-7775 5375);
PAINT MONO (-7775 5375);
DISPLAY INVISIBLE (-7775 5375);
FORCEPROP 1 LAST BODY_TYPE PLUMBING
J 2
(-7775 5425);
DISPLAY 0.872340 (-7775 5425);
PAINT GREEN (-7775 5425);
DISPLAY INVISIBLE (-7775 5425);
FORCEPROP 1 LAST HDL_TAP TRUE
J 2
(-8100 5250);
DISPLAY 0.872340 (-8100 5250);
DISPLAY INVISIBLE (-8100 5250);
FORCEPROP 1 LAST PATH I92
J 2
(-7773 5375);
DISPLAY 0.872340 (-7773 5375);
PAINT GREEN (-7773 5375);
DISPLAY INVISIBLE (-7773 5375);
FORCEADD TAP..1
R 2
(-7775 5425);
FORCEPROP 3 LASTPIN (-7725 5425) SIG_NAME M_B_CPU1_SA_CA<4>
J 0
(-7715 5435);
DISPLAY 0.659574 (-7715 5435);
PAINT MONO (-7715 5435);
DISPLAY INVISIBLE (-7715 5435);
FORCEPROP 1 LASTPIN (-7725 5425) BN 4
J 2
(-7713 5433);
DISPLAY 0.489362 (-7713 5433);
PAINT GREEN (-7713 5433);
FORCEPROP 2 LAST CDS_LIB mstr_standard
J 0
(-7775 5425);
DISPLAY 0.723404 (-7775 5425);
PAINT MONO (-7775 5425);
DISPLAY INVISIBLE (-7775 5425);
FORCEPROP 1 LAST BODY_TYPE PLUMBING
J 2
(-7775 5475);
DISPLAY 0.872340 (-7775 5475);
PAINT GREEN (-7775 5475);
DISPLAY INVISIBLE (-7775 5475);
FORCEPROP 1 LAST HDL_TAP TRUE
J 2
(-8100 5300);
DISPLAY 0.872340 (-8100 5300);
DISPLAY INVISIBLE (-8100 5300);
FORCEPROP 1 LAST PATH I93
J 2
(-7773 5425);
DISPLAY 0.872340 (-7773 5425);
PAINT GREEN (-7773 5425);
DISPLAY INVISIBLE (-7773 5425);
FORCEADD TAP..1
R 2
(-7775 5475);
FORCEPROP 3 LASTPIN (-7725 5475) SIG_NAME M_B_CPU1_SA_CA<5>
J 0
(-7715 5485);
DISPLAY 0.659574 (-7715 5485);
PAINT MONO (-7715 5485);
DISPLAY INVISIBLE (-7715 5485);
FORCEPROP 1 LASTPIN (-7725 5475) BN 5
J 2
(-7713 5483);
DISPLAY 0.489362 (-7713 5483);
PAINT GREEN (-7713 5483);
FORCEPROP 2 LAST CDS_LIB mstr_standard
J 0
(-7775 5475);
DISPLAY 0.723404 (-7775 5475);
PAINT MONO (-7775 5475);
DISPLAY INVISIBLE (-7775 5475);
FORCEPROP 1 LAST BODY_TYPE PLUMBING
J 2
(-7775 5525);
DISPLAY 0.872340 (-7775 5525);
PAINT GREEN (-7775 5525);
DISPLAY INVISIBLE (-7775 5525);
FORCEPROP 1 LAST HDL_TAP TRUE
J 2
(-8100 5350);
DISPLAY 0.872340 (-8100 5350);
DISPLAY INVISIBLE (-8100 5350);
FORCEPROP 1 LAST PATH I94
J 2
(-7773 5475);
DISPLAY 0.872340 (-7773 5475);
PAINT GREEN (-7773 5475);
DISPLAY INVISIBLE (-7773 5475);
FORCEADD TAP..1
R 2
(-7775 5525);
FORCEPROP 3 LASTPIN (-7725 5525) SIG_NAME M_B_CPU1_SA_CA<6>
J 0
(-7715 5535);
DISPLAY 0.659574 (-7715 5535);
PAINT MONO (-7715 5535);
DISPLAY INVISIBLE (-7715 5535);
FORCEPROP 1 LASTPIN (-7725 5525) BN 6
J 2
(-7713 5533);
DISPLAY 0.489362 (-7713 5533);
PAINT GREEN (-7713 5533);
FORCEPROP 2 LAST CDS_LIB mstr_standard
J 0
(-7775 5525);
DISPLAY 0.723404 (-7775 5525);
PAINT MONO (-7775 5525);
DISPLAY INVISIBLE (-7775 5525);
FORCEPROP 1 LAST BODY_TYPE PLUMBING
J 2
(-7775 5575);
DISPLAY 0.872340 (-7775 5575);
PAINT GREEN (-7775 5575);
DISPLAY INVISIBLE (-7775 5575);
FORCEPROP 1 LAST HDL_TAP TRUE
J 2
(-8100 5400);
DISPLAY 0.872340 (-8100 5400);
DISPLAY INVISIBLE (-8100 5400);
FORCEPROP 1 LAST PATH I95
J 2
(-7773 5525);
DISPLAY 0.872340 (-7773 5525);
PAINT GREEN (-7773 5525);
DISPLAY INVISIBLE (-7773 5525);
FORCEADD TAP..1
(-6075 4125);
FORCEPROP 3 LASTPIN (-6125 4125) SIG_NAME M_B_CPU1_SA_DQ<3>
J 0
(-6115 4135);
DISPLAY 0.659574 (-6115 4135);
PAINT MONO (-6115 4135);
DISPLAY INVISIBLE (-6115 4135);
FORCEPROP 1 LASTPIN (-6125 4125) BN 3
J 0
(-6137 4133);
DISPLAY 0.489362 (-6137 4133);
PAINT GREEN (-6137 4133);
FORCEPROP 2 LAST CDS_LIB mstr_standard
J 0
(-6075 4125);
DISPLAY 0.723404 (-6075 4125);
PAINT MONO (-6075 4125);
DISPLAY INVISIBLE (-6075 4125);
FORCEPROP 1 LAST BODY_TYPE PLUMBING
J 0
(-6075 4175);
DISPLAY 0.872340 (-6075 4175);
PAINT GREEN (-6075 4175);
DISPLAY INVISIBLE (-6075 4175);
FORCEPROP 1 LAST HDL_TAP TRUE
J 0
(-5750 4000);
DISPLAY 0.872340 (-5750 4000);
DISPLAY INVISIBLE (-5750 4000);
FORCEPROP 1 LAST PATH I96
J 0
(-6077 4125);
DISPLAY 0.872340 (-6077 4125);
PAINT GREEN (-6077 4125);
DISPLAY INVISIBLE (-6077 4125);
FORCEADD TAP..1
(-6075 4175);
FORCEPROP 3 LASTPIN (-6125 4175) SIG_NAME M_B_CPU1_SA_DQ<4>
J 0
(-6115 4185);
DISPLAY 0.659574 (-6115 4185);
PAINT MONO (-6115 4185);
DISPLAY INVISIBLE (-6115 4185);
FORCEPROP 1 LASTPIN (-6125 4175) BN 4
J 0
(-6137 4183);
DISPLAY 0.489362 (-6137 4183);
PAINT GREEN (-6137 4183);
FORCEPROP 2 LAST CDS_LIB mstr_standard
J 0
(-6075 4175);
DISPLAY 0.723404 (-6075 4175);
PAINT MONO (-6075 4175);
DISPLAY INVISIBLE (-6075 4175);
FORCEPROP 1 LAST BODY_TYPE PLUMBING
J 0
(-6075 4225);
DISPLAY 0.872340 (-6075 4225);
PAINT GREEN (-6075 4225);
DISPLAY INVISIBLE (-6075 4225);
FORCEPROP 1 LAST HDL_TAP TRUE
J 0
(-5750 4050);
DISPLAY 0.872340 (-5750 4050);
DISPLAY INVISIBLE (-5750 4050);
FORCEPROP 1 LAST PATH I97
J 0
(-6077 4175);
DISPLAY 0.872340 (-6077 4175);
PAINT GREEN (-6077 4175);
DISPLAY INVISIBLE (-6077 4175);
FORCEADD TAP..1
(-6075 4225);
FORCEPROP 3 LASTPIN (-6125 4225) SIG_NAME M_B_CPU1_SA_DQ<5>
J 0
(-6115 4235);
DISPLAY 0.659574 (-6115 4235);
PAINT MONO (-6115 4235);
DISPLAY INVISIBLE (-6115 4235);
FORCEPROP 1 LASTPIN (-6125 4225) BN 5
J 0
(-6137 4233);
DISPLAY 0.489362 (-6137 4233);
PAINT GREEN (-6137 4233);
FORCEPROP 2 LAST CDS_LIB mstr_standard
J 0
(-6075 4225);
DISPLAY 0.723404 (-6075 4225);
PAINT MONO (-6075 4225);
DISPLAY INVISIBLE (-6075 4225);
FORCEPROP 1 LAST BODY_TYPE PLUMBING
J 0
(-6075 4275);
DISPLAY 0.872340 (-6075 4275);
PAINT GREEN (-6075 4275);
DISPLAY INVISIBLE (-6075 4275);
FORCEPROP 1 LAST HDL_TAP TRUE
J 0
(-5750 4100);
DISPLAY 0.872340 (-5750 4100);
DISPLAY INVISIBLE (-5750 4100);
FORCEPROP 1 LAST PATH I98
J 0
(-6077 4225);
DISPLAY 0.872340 (-6077 4225);
PAINT GREEN (-6077 4225);
DISPLAY INVISIBLE (-6077 4225);
FORCEADD TAP..1
(-6075 4275);
FORCEPROP 3 LASTPIN (-6125 4275) SIG_NAME M_B_CPU1_SA_DQ<6>
J 0
(-6115 4285);
DISPLAY 0.659574 (-6115 4285);
PAINT MONO (-6115 4285);
DISPLAY INVISIBLE (-6115 4285);
FORCEPROP 1 LASTPIN (-6125 4275) BN 6
J 0
(-6137 4283);
DISPLAY 0.489362 (-6137 4283);
PAINT GREEN (-6137 4283);
FORCEPROP 2 LAST CDS_LIB mstr_standard
J 0
(-6075 4275);
DISPLAY 0.723404 (-6075 4275);
PAINT MONO (-6075 4275);
DISPLAY INVISIBLE (-6075 4275);
FORCEPROP 1 LAST BODY_TYPE PLUMBING
J 0
(-6075 4325);
DISPLAY 0.872340 (-6075 4325);
PAINT GREEN (-6075 4325);
DISPLAY INVISIBLE (-6075 4325);
FORCEPROP 1 LAST HDL_TAP TRUE
J 0
(-5750 4150);
DISPLAY 0.872340 (-5750 4150);
DISPLAY INVISIBLE (-5750 4150);
FORCEPROP 1 LAST PATH I99
J 0
(-6077 4275);
DISPLAY 0.872340 (-6077 4275);
PAINT GREEN (-6077 4275);
DISPLAY INVISIBLE (-6077 4275);
FORCEADD QUANTA_TITLE_BLOCK_C..1
(-100 100);
FORCEPROP 0 LAST CDS_CON_LAST_MODIFIED Thu Sep 14 16:12:10 2023
J 0
(-1985 115);
DISPLAY INVISIBLE (-1985 115);
FORCEPROP 1 LAST CUSTOM_TXT_CDS <CON_LAST_MODIFIED>
J 0
(-1985 115);
DISPLAY 0.978723 (-1985 115);
FORCEPROP 2 LAST CUSTOM_TXT_CDS <XR_PAGE_TITLE>
J 0
(-7990 5350);
DISPLAY 0.638298 (-7990 5350);
PAINT PINK (-7990 5350);
DISPLAY INVISIBLE (-7990 5350);
FORCEPROP 1 LAST CUSTOM_TXT_CDS <NAME_2>
J 0
(-3275 150);
FORCEPROP 1 LAST CUSTOM_TXT_CDS <NAME_1>
J 0
(-3275 275);
FORCEPROP 1 LAST CUSTOM_TXT_CDS <Q_NUMBER>
J 0
(-1503 203);
DISPLAY 1.212766 (-1503 203);
FORCEPROP 1 LAST CUSTOM_TXT_CDS <Q_PROJ>
J 0
(-2482 202);
DISPLAY 1.212766 (-2482 202);
FORCEPROP 1 LAST CUSTOM_TXT_CDS <Q_REV>
J 0
(-284 203);
DISPLAY 1.212766 (-284 203);
FORCEPROP 1 LAST CUSTOM_TXT_CDS <CON_PAGE_NUM> OF <CON_TOTAL_PAGES>
J 0
(-546 118);
DISPLAY 0.978723 (-546 118);
FORCEPROP 1 LAST Q_TITLE DDR5 - CPU1 CHB
J 0
(-9375 150);
DISPLAY 2.446809 (-9375 150);
PAINT GREEN (-9375 150);
FORCEPROP 2 LAST PAGE_BORDER TRUE
J 0
(-7990 5350);
DISPLAY 0.638298 (-7990 5350);
PAINT PINK (-7990 5350);
DISPLAY INVISIBLE (-7990 5350);
FORCEPROP 2 LAST CDS_LIB pure_quanta
J 0
(-100 100);
DISPLAY INVISIBLE (-100 100);
FORCEPROP 1 LAST CDS_LMAN_SYM_OUTLINE -9475,6775,100,-125
J 0
(-100 100);
DISPLAY 0.468085 (-100 100);
PAINT GREEN (-100 100);
DISPLAY INVISIBLE (-100 100);
FORCEPROP 2 LAST CDS_XR_PAGE_TITLE CR-99 : @T6G_MB_LIB.T6G(SCH_1):PAGE99
J 0
(-7990 5350);
DISPLAY 0.638298 (-7990 5350);
PAINT PINK (-7990 5350);
DISPLAY INVISIBLE (-7990 5350);
FORCEPROP 1 LAST Q_DEPT BU9
J 1
(-3863 149);
DISPLAY 1.957447 (-3863 149);
PAINT GREEN (-3863 149);
DISPLAY INVISIBLE (-3863 149);
FORCEPROP 1 LAST COMMENT_BODY TRUE
J 0
(-88 87);
DISPLAY 0.978723 (-88 87);
PAINT GREEN (-88 87);
DISPLAY INVISIBLE (-88 87);
FORCEADD DNS..2
(-8475 2425);
PAINT RED (-8475 2425);
FORCEPROP 2 LAST CDS_LIB mstr_misc
J 0
(-8475 2425);
DISPLAY INVISIBLE (-8475 2425);
FORCEPROP 1 LAST COMMENT_BODY TRUE
R 1
J 0
(-8400 2200);
DISPLAY 0.872340 (-8400 2200);
PAINT PEACH (-8400 2200);
DISPLAY INVISIBLE (-8400 2200);
WIRE 17 -1 (-7825 4150)(-7825 4175);
WIRE 17 -1 (-7825 4150)(-7825 4100);
WIRE 17 -1 (-7825 4175)(-8325 4175);
FORCEPROP 2 LAST SIG_NAME M_B_CPU1_SA_CB<7:0>
J 0
(-8275 4185);
DISPLAY 0.489362 (-8275 4185);
WIRE 17 -1 (-7825 4050)(-7825 4000);
WIRE 17 -1 (-7825 4050)(-7825 4100);
WIRE 17 -1 (-7825 3950)(-7825 4000);
WIRE 17 -1 (-7825 3900)(-7825 3950);
WIRE 17 -1 (-7825 3850)(-7825 3900);
WIRE 17 -1 (-7825 3800)(-7825 3850);
WIRE 17 -1 (-7825 3700)(-7825 3725);
WIRE 17 -1 (-7825 3700)(-7825 3650);
WIRE 17 -1 (-7825 3725)(-8325 3725);
FORCEPROP 2 LAST SIG_NAME M_B_CPU1_SB_CB<7:0>
J 0
(-8275 3735);
DISPLAY 0.489362 (-8275 3735);
WIRE 17 -1 (-7825 4850)(-7825 4900);
WIRE 17 -1 (-7825 4900)(-7825 4950);
WIRE 17 -1 (-7825 4950)(-7825 5000);
WIRE 17 -1 (-7825 5000)(-7825 5050);
WIRE 17 -1 (-7825 5050)(-7825 5100);
WIRE 17 -1 (-7825 5100)(-7825 5150);
WIRE 17 -1 (-7825 5150)(-7825 5175);
WIRE 17 -1 (-7825 5175)(-8325 5175);
FORCEPROP 2 LAST SIG_NAME M_B_CPU1_SB_CA<6:0>
J 0
(-8310 5185);
DISPLAY 0.489362 (-8310 5185);
WIRE 17 -1 (-7825 5300)(-7825 5350);
WIRE 17 -1 (-7825 5250)(-7825 5300);
WIRE 17 -1 (-7825 5350)(-7825 5400);
WIRE 17 -1 (-7825 5400)(-7825 5450);
WIRE 17 -1 (-7825 5450)(-7825 5500);
WIRE 17 -1 (-7825 5500)(-7825 5550);
WIRE 17 -1 (-7825 5550)(-7825 5575);
WIRE 17 -1 (-7825 5575)(-8325 5575);
FORCEPROP 2 LAST SIG_NAME M_B_CPU1_SA_CA<6:0>
J 0
(-8310 5585);
DISPLAY 0.489362 (-8310 5585);
WIRE 17 -1 (-7825 3600)(-7825 3650);
WIRE 17 -1 (-7825 3600)(-7825 3550);
WIRE 17 -1 (-7825 3500)(-7825 3550);
WIRE 17 -1 (-7825 3450)(-7825 3500);
WIRE 17 -1 (-7825 3400)(-7825 3450);
WIRE 17 -1 (-7825 3350)(-7825 3400);
WIRE 17 -1 (-6025 5550)(-6025 5500);
WIRE 17 -1 (-6025 5575)(-6025 5550);
WIRE 17 -1 (-6025 5500)(-6025 5450);
WIRE 17 -1 (-6025 5450)(-6025 5400);
WIRE 17 -1 (-6025 5575)(-5375 5575);
FORCEPROP 2 LAST SIG_NAME M_B_CPU1_SA_DQ<31:0>
J 0
(-5960 5585);
DISPLAY 0.489362 (-5960 5585);
WIRE 17 -1 (-6025 5400)(-6025 5350);
WIRE 17 -1 (-6025 5350)(-6025 5300);
WIRE 17 -1 (-6025 5300)(-6025 5250);
WIRE 17 -1 (-6025 5250)(-6025 5200);
WIRE 17 -1 (-6025 5200)(-6025 5150);
WIRE 17 -1 (-6025 5150)(-6025 5100);
WIRE 17 -1 (-6025 5100)(-6025 5050);
WIRE 17 -1 (-6025 5050)(-6025 5000);
WIRE 17 -1 (-6025 5000)(-6025 4950);
WIRE 17 -1 (-6025 4950)(-6025 4900);
WIRE 17 -1 (-6025 4900)(-6025 4850);
WIRE 17 -1 (-6025 4850)(-6025 4800);
WIRE 17 -1 (-6025 4750)(-6025 4800);
WIRE 17 -1 (-6025 4700)(-6025 4750);
WIRE 17 -1 (-6025 4650)(-6025 4700);
WIRE 17 -1 (-6025 4600)(-6025 4650);
WIRE 17 -1 (-6025 4600)(-6025 4550);
WIRE 17 -1 (-6025 4550)(-6025 4500);
WIRE 17 -1 (-6025 4500)(-6025 4450);
WIRE 17 -1 (-6025 4450)(-6025 4400);
WIRE 17 -1 (-6025 4400)(-6025 4350);
WIRE 17 -1 (-6025 4350)(-6025 4300);
WIRE 17 -1 (-6025 4300)(-6025 4250);
WIRE 17 -1 (-6025 4250)(-6025 4200);
WIRE 17 -1 (-6025 4150)(-6025 4200);
WIRE 17 -1 (-6025 4100)(-6025 4150);
WIRE 17 -1 (-6025 4050)(-6025 4100);
WIRE 17 -1 (-6025 4000)(-6025 4050);
WIRE 17 -1 (-6025 3925)(-6025 3900);
WIRE 17 -1 (-6025 3925)(-5375 3925);
FORCEPROP 2 LAST SIG_NAME M_B_CPU1_SB_DQ<31:0>
J 0
(-5960 3935);
DISPLAY 0.489362 (-5960 3935);
WIRE 17 -1 (-6025 3900)(-6025 3850);
WIRE 17 -1 (-6025 3850)(-6025 3800);
WIRE 17 -1 (-6025 3800)(-6025 3750);
WIRE 17 -1 (-6025 3750)(-6025 3700);
WIRE 17 -1 (-6025 3700)(-6025 3650);
WIRE 17 -1 (-6025 3650)(-6025 3600);
WIRE 17 -1 (-6025 3600)(-6025 3550);
WIRE 17 -1 (-6025 3550)(-6025 3500);
WIRE 17 -1 (-6025 3500)(-6025 3450);
WIRE 17 -1 (-6025 3450)(-6025 3400);
WIRE 17 -1 (-6025 3400)(-6025 3350);
WIRE 17 -1 (-6025 3350)(-6025 3300);
WIRE 17 -1 (-6025 3300)(-6025 3250);
WIRE 17 -1 (-6025 3250)(-6025 3200);
WIRE 17 -1 (-6025 3200)(-6025 3150);
WIRE 17 -1 (-6025 3100)(-6025 3150);
WIRE 17 -1 (-6025 3050)(-6025 3100);
WIRE 17 -1 (-6025 3000)(-6025 3050);
WIRE 17 -1 (-6025 2950)(-6025 3000);
WIRE 17 -1 (-6025 2950)(-6025 2900);
WIRE 17 -1 (-6025 2900)(-6025 2850);
WIRE 17 -1 (-6025 2850)(-6025 2800);
WIRE 17 -1 (-6025 2800)(-6025 2750);
WIRE 17 -1 (-6025 2750)(-6025 2700);
WIRE 17 -1 (-6025 2700)(-6025 2650);
WIRE 17 -1 (-6025 2650)(-6025 2600);
WIRE 17 -1 (-6025 2600)(-6025 2550);
WIRE 17 -1 (-6025 2500)(-6025 2550);
WIRE 17 -1 (-6025 2450)(-6025 2500);
WIRE 17 -1 (-6025 2400)(-6025 2450);
WIRE 17 -1 (-6025 2350)(-6025 2400);
WIRE 17 -1 (-3200 4375)(-3200 4275);
WIRE 17 -1 (-3200 4475)(-3200 4375);
WIRE 17 -1 (-3200 4275)(-3200 4175);
WIRE 17 -1 (-3200 4175)(-3200 4075);
WIRE 17 -1 (-3200 4500)(-3200 4475);
WIRE 17 -1 (-3200 4500)(-2500 4500);
FORCEPROP 2 LAST SIG_NAME M_B_CPU1_SA_DQS_DN<9:0>
J 0
(-3135 4510);
DISPLAY 0.489362 (-3135 4510);
WIRE 17 -1 (-3400 4325)(-3400 4225);
WIRE 17 -1 (-3400 4425)(-3400 4325);
WIRE 17 -1 (-3400 4225)(-3400 4125);
WIRE 17 -1 (-3400 4025)(-3400 4125);
WIRE 17 -1 (-3400 4525)(-3400 4425);
WIRE 17 -1 (-3400 4550)(-3400 4525);
WIRE 17 -1 (-3400 3925)(-3400 4025);
WIRE 17 -1 (-3400 3825)(-3400 3925);
WIRE 17 -1 (-3400 4550)(-2500 4550);
FORCEPROP 2 LAST SIG_NAME M_B_CPU1_SA_DQS_DP<9:0>
J 0
(-3135 4560);
DISPLAY 0.489362 (-3135 4560);
WIRE 17 -1 (-3400 3475)(-3400 3375);
WIRE 17 -1 (-3400 3500)(-3400 3475);
WIRE 17 -1 (-3400 3375)(-3400 3275);
WIRE 17 -1 (-3400 3275)(-3400 3175);
WIRE 17 -1 (-3400 3500)(-2500 3500);
FORCEPROP 2 LAST SIG_NAME M_B_CPU1_SB_DQS_DP<9:0>
J 0
(-3135 3510);
DISPLAY 0.489362 (-3135 3510);
WIRE 17 -1 (-3200 3425)(-3200 3325);
WIRE 17 -1 (-3200 3450)(-3200 3425);
WIRE 17 -1 (-3200 3325)(-3200 3225);
WIRE 17 -1 (-3200 3225)(-3200 3125);
WIRE 17 -1 (-3200 3450)(-2500 3450);
FORCEPROP 2 LAST SIG_NAME M_B_CPU1_SB_DQS_DN<9:0>
J 0
(-3135 3460);
DISPLAY 0.489362 (-3135 3460);
WIRE 17 -1 (-3400 3175)(-3400 3075);
WIRE 17 -1 (-3200 3675)(-3200 3575);
WIRE 17 -1 (-3200 3775)(-3200 3675);
WIRE 17 -1 (-3200 3775)(-3200 3875);
WIRE 17 -1 (-3200 3875)(-3200 3975);
WIRE 17 -1 (-3200 3975)(-3200 4075);
WIRE 17 -1 (-3400 3725)(-3400 3625);
WIRE 17 -1 (-3400 3825)(-3400 3725);
WIRE 17 -1 (-3200 2625)(-3200 2525);
WIRE 17 -1 (-3200 2725)(-3200 2625);
WIRE 17 -1 (-3200 2725)(-3200 2825);
WIRE 17 -1 (-3200 2825)(-3200 2925);
WIRE 17 -1 (-3200 2925)(-3200 3025);
WIRE 17 -1 (-3200 3125)(-3200 3025);
WIRE 17 -1 (-3400 2675)(-3400 2575);
WIRE 17 -1 (-3400 2775)(-3400 2675);
WIRE 17 -1 (-3400 2775)(-3400 2875);
WIRE 17 -1 (-3400 2875)(-3400 2975);
WIRE 17 -1 (-3400 2975)(-3400 3075);
WIRE 16 -1 (-6475 1275)(-6475 1350);
WIRE 16 -1 (-8725 3150)(-8725 3225);
WIRE 16 -1 (-8500 2525)(-8500 2550);
WIRE 16 -1 (-8625 3075)(-7525 3075);
WIRE 16 -1 (-8625 3450)(-8625 3075);
WIRE 16 -1 (-8625 3500)(-8625 3450);
WIRE 16 -1 (-8725 3450)(-8625 3450);
WIRE 16 -1 (-8725 3425)(-8725 3450);
WIRE 16 -1 (-8300 2275)(-8300 2675);
WIRE 16 -1 (-8300 2275)(-8500 2275);
WIRE 16 -1 (-7525 2675)(-8300 2675);
FORCEPROP 2 LAST SIG_NAME PWRGD_CHB_CPU1_DIMM
J 0
(-8100 2685);
DISPLAY 0.489362 (-8100 2685);
FORCEPROP 2 LASTPROP $XRERR UNIQUE?
J 0
(-8340 2685);
DISPLAY 0.638298 (-8340 2685);
PAINT MONO (-8340 2685);
DISPLAY INVISIBLE (-8340 2685);
WIRE 16 -1 (-8500 2325)(-8500 2275);
WIRE 16 -1 (-8500 2275)(-8525 2275);
WIRE 16 -1 (-7525 2975)(-8100 2975);
FORCEPROP 2 LAST SIG_NAME I3C_SPD_DDRB_CPU1_SDA
J 0
(-8010 2985);
DISPLAY 0.446809 (-8010 2985);
FORCEPROP 2 LASTPROP $XRERR UNIQUE?
J 0
(-8250 2985);
DISPLAY 0.638298 (-8250 2985);
PAINT MONO (-8250 2985);
DISPLAY INVISIBLE (-8250 2985);
WIRE 16 -1 (-7925 2750)(-8425 2750);
FORCEPROP 2 LAST SIG_NAME I3C_SPD_DDRAF_CPU1_SCL
J 0
(-8485 2760);
DISPLAY 0.489362 (-8485 2760);
WIRE 16 -1 (-8325 2975)(-8300 2975);
WIRE 16 -1 (-8325 2875)(-8325 2975);
WIRE 16 -1 (-8325 2875)(-8825 2875);
FORCEPROP 2 LAST SIG_NAME I3C_SPD_DDRAF_CPU1_SDA
J 0
(-8835 2885);
DISPLAY 0.489362 (-8835 2885);
WIRE 16 -1 (-7525 3025)(-8525 3025);
FORCEPROP 2 LAST SIG_NAME PD_CHB_CPU1_DIMM_SAA
J 0
(-8500 3035);
DISPLAY 0.489362 (-8500 3035);
WIRE 16 -1 (-7525 2925)(-7625 2925);
FORCEPROP 2 LAST SIG_NAME I3C_SPD_DDRB_CPU1_SCL
J 0
(-8010 2935);
DISPLAY 0.446809 (-8010 2935);
FORCEPROP 2 LASTPROP $XRERR UNIQUE?
J 0
(-8250 2935);
DISPLAY 0.638298 (-8250 2935);
PAINT MONO (-8250 2935);
DISPLAY INVISIBLE (-8250 2935);
WIRE 16 -1 (-7625 2925)(-7625 2750);
WIRE 16 -1 (-7625 2750)(-7725 2750);
WIRE 16 -1 (-7525 2075)(-8325 2075);
FORCEPROP 2 LAST SIG_NAME M_B_CPU1_SB_RSP<0>
J 0
(-8275 2085);
DISPLAY 0.489362 (-8275 2085);
WIRE 16 -1 (-6325 3675)(-6125 3675);
WIRE 16 -1 (-1875 1925)(-2175 1925);
WIRE 16 -1 (-2175 1975)(-2175 1925);
WIRE 16 -1 (-2175 1925)(-2175 1875);
WIRE 16 -1 (-1875 1875)(-2175 1875);
WIRE 16 -1 (-2175 1875)(-2175 1775);
WIRE 16 -1 (-1875 1975)(-2175 1975);
WIRE 16 -1 (-2175 2025)(-2175 1975);
WIRE 16 -1 (-1875 2025)(-2175 2025);
WIRE 16 -1 (-2175 2075)(-2175 2025);
WIRE 16 -1 (-1875 2075)(-2175 2075);
WIRE 16 -1 (-2175 2125)(-2175 2075);
WIRE 16 -1 (-1875 2125)(-2175 2125);
WIRE 16 -1 (-2175 2175)(-2175 2125);
WIRE 16 -1 (-1875 2175)(-2175 2175);
WIRE 16 -1 (-2175 2225)(-2175 2175);
WIRE 16 -1 (-1875 2225)(-2175 2225);
WIRE 16 -1 (-2175 2275)(-2175 2225);
WIRE 16 -1 (-1875 2275)(-2175 2275);
WIRE 16 -1 (-2175 2325)(-2175 2275);
WIRE 16 -1 (-1875 2325)(-2175 2325);
WIRE 16 -1 (-2175 2375)(-2175 2325);
WIRE 16 -1 (-1875 2375)(-2175 2375);
WIRE 16 -1 (-2175 2425)(-2175 2375);
WIRE 16 -1 (-1875 2425)(-2175 2425);
WIRE 16 -1 (-2175 2475)(-2175 2425);
WIRE 16 -1 (-1875 2475)(-2175 2475);
WIRE 16 -1 (-2175 2525)(-2175 2475);
WIRE 16 -1 (-1875 2525)(-2175 2525);
WIRE 16 -1 (-2175 2575)(-2175 2525);
WIRE 16 -1 (-1875 2575)(-2175 2575);
WIRE 16 -1 (-2175 2625)(-2175 2575);
WIRE 16 -1 (-1875 2625)(-2175 2625);
WIRE 16 -1 (-2175 2675)(-2175 2625);
WIRE 16 -1 (-1875 2675)(-2175 2675);
WIRE 16 -1 (-2175 2725)(-2175 2675);
WIRE 16 -1 (-1875 2725)(-2175 2725);
WIRE 16 -1 (-2175 2775)(-2175 2725);
WIRE 16 -1 (-1875 2775)(-2175 2775);
WIRE 16 -1 (-2175 2825)(-2175 2775);
WIRE 16 -1 (-1875 2825)(-2175 2825);
WIRE 16 -1 (-2175 2875)(-2175 2825);
WIRE 16 -1 (-1875 2875)(-2175 2875);
WIRE 16 -1 (-2175 2925)(-2175 2875);
WIRE 16 -1 (-1875 2925)(-2175 2925);
WIRE 16 -1 (-2175 2975)(-2175 2925);
WIRE 16 -1 (-1875 2975)(-2175 2975);
WIRE 16 -1 (-2175 3025)(-2175 2975);
WIRE 16 -1 (-1875 3025)(-2175 3025);
WIRE 16 -1 (-2175 3075)(-2175 3025);
WIRE 16 -1 (-1875 3075)(-2175 3075);
WIRE 16 -1 (-2175 3125)(-2175 3075);
WIRE 16 -1 (-1875 3125)(-2175 3125);
WIRE 16 -1 (-2175 3175)(-2175 3125);
WIRE 16 -1 (-1875 3175)(-2175 3175);
WIRE 16 -1 (-2175 3225)(-2175 3175);
WIRE 16 -1 (-1875 3225)(-2175 3225);
WIRE 16 -1 (-2175 3275)(-2175 3225);
WIRE 16 -1 (-1875 3275)(-2175 3275);
WIRE 16 -1 (-2175 3325)(-2175 3275);
WIRE 16 -1 (-1875 3325)(-2175 3325);
WIRE 16 -1 (-2175 3375)(-2175 3325);
WIRE 16 -1 (-1875 3375)(-2175 3375);
WIRE 16 -1 (-2175 3425)(-2175 3375);
WIRE 16 -1 (-1875 3425)(-2175 3425);
WIRE 16 -1 (-2175 3475)(-2175 3425);
WIRE 16 -1 (-1875 3475)(-2175 3475);
WIRE 16 -1 (-2175 3525)(-2175 3475);
WIRE 16 -1 (-1875 3525)(-2175 3525);
WIRE 16 -1 (-2175 3575)(-2175 3525);
WIRE 16 -1 (-1875 3575)(-2175 3575);
WIRE 16 -1 (-2175 3625)(-2175 3575);
WIRE 16 -1 (-1875 3625)(-2175 3625);
WIRE 16 -1 (-2175 3675)(-2175 3625);
WIRE 16 -1 (-1875 3675)(-2175 3675);
WIRE 16 -1 (-2175 3725)(-2175 3675);
WIRE 16 -1 (-1875 3725)(-2175 3725);
WIRE 16 -1 (-2175 3775)(-2175 3725);
WIRE 16 -1 (-1875 3775)(-2175 3775);
WIRE 16 -1 (-2175 3825)(-2175 3775);
WIRE 16 -1 (-1875 3825)(-2175 3825);
WIRE 16 -1 (-2175 3875)(-2175 3825);
WIRE 16 -1 (-1875 3875)(-2175 3875);
WIRE 16 -1 (-2175 3925)(-2175 3875);
WIRE 16 -1 (-1875 3925)(-2175 3925);
WIRE 16 -1 (-2175 3975)(-2175 3925);
WIRE 16 -1 (-1875 3975)(-2175 3975);
WIRE 16 -1 (-2175 4025)(-2175 3975);
WIRE 16 -1 (-1875 4025)(-2175 4025);
WIRE 16 -1 (-2175 4075)(-2175 4025);
WIRE 16 -1 (-2175 4125)(-2175 4075);
WIRE 16 -1 (-1875 4075)(-2175 4075);
WIRE 16 -1 (-1875 4125)(-2175 4125);
WIRE 16 -1 (-2175 4175)(-2175 4125);
WIRE 16 -1 (-1875 4175)(-2175 4175);
WIRE 16 -1 (-2175 4225)(-2175 4175);
WIRE 16 -1 (-1875 4225)(-2175 4225);
WIRE 16 -1 (-2175 4275)(-2175 4225);
WIRE 16 -1 (-1875 4275)(-2175 4275);
WIRE 16 -1 (-2175 4325)(-2175 4275);
WIRE 16 -1 (-1875 4325)(-2175 4325);
WIRE 16 -1 (-2175 4375)(-2175 4325);
WIRE 16 -1 (-1875 4375)(-2175 4375);
WIRE 16 -1 (-2175 4425)(-2175 4375);
WIRE 16 -1 (-1875 4425)(-2175 4425);
WIRE 16 -1 (-2175 4475)(-2175 4425);
WIRE 16 -1 (-1875 4475)(-2175 4475);
WIRE 16 -1 (-2175 4525)(-2175 4475);
WIRE 16 -1 (-1875 4525)(-2175 4525);
WIRE 16 -1 (-2175 4575)(-2175 4525);
WIRE 16 -1 (-1875 4575)(-2175 4575);
WIRE 16 -1 (-2175 4625)(-2175 4575);
WIRE 16 -1 (-1875 4625)(-2175 4625);
WIRE 16 -1 (-2175 4675)(-2175 4625);
WIRE 16 -1 (-1875 4675)(-2175 4675);
WIRE 16 -1 (-2175 4725)(-2175 4675);
WIRE 16 -1 (-1875 4725)(-2175 4725);
WIRE 16 -1 (-2175 4775)(-2175 4725);
WIRE 16 -1 (-1875 4775)(-2175 4775);
WIRE 16 -1 (-2175 4825)(-2175 4775);
WIRE 16 -1 (-1875 4825)(-2175 4825);
WIRE 16 -1 (-2175 4875)(-2175 4825);
WIRE 16 -1 (-1875 4875)(-2175 4875);
WIRE 16 -1 (-2175 4925)(-2175 4875);
WIRE 16 -1 (-1875 4925)(-2175 4925);
WIRE 16 -1 (-2175 4975)(-2175 4925);
WIRE 16 -1 (-1875 4975)(-2175 4975);
WIRE 16 -1 (-375 1975)(-375 1875);
WIRE 16 -1 (-375 2025)(-375 1975);
WIRE 16 -1 (-375 1975)(-675 1975);
WIRE 16 -1 (-375 1875)(-375 1825);
WIRE 16 -1 (-375 1875)(-675 1875);
WIRE 16 -1 (-375 1825)(-375 1775);
WIRE 16 -1 (-375 1825)(-675 1825);
WIRE 16 -1 (-375 2075)(-375 2025);
WIRE 16 -1 (-375 2025)(-675 2025);
WIRE 16 -1 (-375 2125)(-375 2075);
WIRE 16 -1 (-375 2075)(-675 2075);
WIRE 16 -1 (-375 1775)(-375 1600);
WIRE 16 -1 (-375 1775)(-675 1775);
WIRE 16 -1 (-375 2175)(-375 2125);
WIRE 16 -1 (-375 2125)(-675 2125);
WIRE 16 -1 (-375 2225)(-375 2175);
WIRE 16 -1 (-375 2175)(-675 2175);
WIRE 16 -1 (-375 2275)(-375 2225);
WIRE 16 -1 (-375 2225)(-675 2225);
WIRE 16 -1 (-375 2325)(-375 2275);
WIRE 16 -1 (-375 2275)(-675 2275);
WIRE 16 -1 (-375 2375)(-375 2325);
WIRE 16 -1 (-375 2325)(-675 2325);
WIRE 16 -1 (-375 2425)(-375 2375);
WIRE 16 -1 (-375 2375)(-675 2375);
WIRE 16 -1 (-375 2475)(-375 2425);
WIRE 16 -1 (-375 2425)(-675 2425);
WIRE 16 -1 (-375 2525)(-375 2475);
WIRE 16 -1 (-375 2475)(-675 2475);
WIRE 16 -1 (-375 2575)(-375 2525);
WIRE 16 -1 (-375 2525)(-675 2525);
WIRE 16 -1 (-375 2625)(-375 2575);
WIRE 16 -1 (-375 2575)(-675 2575);
WIRE 16 -1 (-375 2675)(-375 2625);
WIRE 16 -1 (-375 2625)(-675 2625);
WIRE 16 -1 (-375 2725)(-375 2675);
WIRE 16 -1 (-375 2675)(-675 2675);
WIRE 16 -1 (-375 2775)(-375 2725);
WIRE 16 -1 (-375 2725)(-675 2725);
WIRE 16 -1 (-375 2825)(-375 2775);
WIRE 16 -1 (-375 2775)(-675 2775);
WIRE 16 -1 (-375 2875)(-375 2825);
WIRE 16 -1 (-375 2825)(-675 2825);
WIRE 16 -1 (-375 2925)(-375 2875);
WIRE 16 -1 (-375 2875)(-675 2875);
WIRE 16 -1 (-375 2975)(-375 2925);
WIRE 16 -1 (-375 2925)(-675 2925);
WIRE 16 -1 (-375 3025)(-375 2975);
WIRE 16 -1 (-375 2975)(-675 2975);
WIRE 16 -1 (-375 3075)(-375 3025);
WIRE 16 -1 (-375 3025)(-675 3025);
WIRE 16 -1 (-375 3125)(-375 3075);
WIRE 16 -1 (-375 3075)(-675 3075);
WIRE 16 -1 (-375 3175)(-375 3125);
WIRE 16 -1 (-375 3125)(-675 3125);
WIRE 16 -1 (-375 3225)(-375 3175);
WIRE 16 -1 (-375 3175)(-675 3175);
WIRE 16 -1 (-375 3275)(-375 3225);
WIRE 16 -1 (-375 3225)(-675 3225);
WIRE 16 -1 (-375 3325)(-375 3275);
WIRE 16 -1 (-375 3275)(-675 3275);
WIRE 16 -1 (-375 3375)(-375 3325);
WIRE 16 -1 (-375 3325)(-675 3325);
WIRE 16 -1 (-375 3425)(-375 3375);
WIRE 16 -1 (-375 3375)(-675 3375);
WIRE 16 -1 (-375 3475)(-375 3425);
WIRE 16 -1 (-375 3425)(-675 3425);
WIRE 16 -1 (-375 3525)(-375 3475);
WIRE 16 -1 (-375 3475)(-675 3475);
WIRE 16 -1 (-375 3575)(-375 3525);
WIRE 16 -1 (-375 3525)(-675 3525);
WIRE 16 -1 (-375 3625)(-375 3575);
WIRE 16 -1 (-375 3575)(-675 3575);
WIRE 16 -1 (-375 3675)(-375 3625);
WIRE 16 -1 (-375 3625)(-675 3625);
WIRE 16 -1 (-375 3725)(-375 3675);
WIRE 16 -1 (-375 3675)(-675 3675);
WIRE 16 -1 (-375 3775)(-375 3725);
WIRE 16 -1 (-375 3725)(-675 3725);
WIRE 16 -1 (-375 3825)(-375 3775);
WIRE 16 -1 (-375 3775)(-675 3775);
WIRE 16 -1 (-375 3875)(-375 3825);
WIRE 16 -1 (-375 3825)(-675 3825);
WIRE 16 -1 (-375 3925)(-375 3875);
WIRE 16 -1 (-375 3875)(-675 3875);
WIRE 16 -1 (-375 3975)(-375 3925);
WIRE 16 -1 (-375 3925)(-675 3925);
WIRE 16 -1 (-375 4025)(-375 3975);
WIRE 16 -1 (-375 3975)(-675 3975);
WIRE 16 -1 (-375 4075)(-375 4025);
WIRE 16 -1 (-375 4025)(-675 4025);
WIRE 16 -1 (-375 4125)(-375 4075);
WIRE 16 -1 (-375 4075)(-675 4075);
WIRE 16 -1 (-375 4175)(-375 4125);
WIRE 16 -1 (-375 4125)(-675 4125);
WIRE 16 -1 (-375 4225)(-375 4175);
WIRE 16 -1 (-375 4175)(-675 4175);
WIRE 16 -1 (-375 4275)(-375 4225);
WIRE 16 -1 (-375 4225)(-675 4225);
WIRE 16 -1 (-375 4325)(-375 4275);
WIRE 16 -1 (-375 4275)(-675 4275);
WIRE 16 -1 (-375 4375)(-375 4325);
WIRE 16 -1 (-375 4325)(-675 4325);
WIRE 16 -1 (-375 4425)(-375 4375);
WIRE 16 -1 (-375 4375)(-675 4375);
WIRE 16 -1 (-375 4475)(-375 4425);
WIRE 16 -1 (-375 4425)(-675 4425);
WIRE 16 -1 (-375 4525)(-375 4475);
WIRE 16 -1 (-375 4475)(-675 4475);
WIRE 16 -1 (-375 4575)(-375 4525);
WIRE 16 -1 (-375 4525)(-675 4525);
WIRE 16 -1 (-375 4625)(-375 4575);
WIRE 16 -1 (-375 4575)(-675 4575);
WIRE 16 -1 (-375 4675)(-375 4625);
WIRE 16 -1 (-375 4625)(-675 4625);
WIRE 16 -1 (-375 4725)(-375 4675);
WIRE 16 -1 (-375 4675)(-675 4675);
WIRE 16 -1 (-375 4775)(-375 4725);
WIRE 16 -1 (-375 4725)(-675 4725);
WIRE 16 -1 (-375 4825)(-375 4775);
WIRE 16 -1 (-375 4775)(-675 4775);
WIRE 16 -1 (-375 4875)(-375 4825);
WIRE 16 -1 (-375 4825)(-675 4825);
WIRE 16 -1 (-375 4925)(-375 4875);
WIRE 16 -1 (-375 4875)(-675 4875);
WIRE 16 -1 (-375 4975)(-375 4925);
WIRE 16 -1 (-375 4925)(-675 4925);
WIRE 16 -1 (-375 5025)(-375 4975);
WIRE 16 -1 (-375 4975)(-675 4975);
WIRE 16 -1 (-375 5075)(-375 5025);
WIRE 16 -1 (-375 5025)(-675 5025);
WIRE 16 -1 (-375 5125)(-375 5075);
WIRE 16 -1 (-375 5075)(-675 5075);
WIRE 16 -1 (-375 5125)(-675 5125);
WIRE 16 -1 (-2300 5300)(-2300 5425);
WIRE 16 -1 (-2300 5300)(-2875 5300);
WIRE 16 -1 (-2875 5300)(-2875 5425);
WIRE 16 -1 (-2875 5300)(-2875 5225);
WIRE 16 -1 (-2300 5725)(-2175 5725);
WIRE 16 -1 (-2300 5725)(-2300 5625);
WIRE 16 -1 (-2300 5725)(-2875 5725);
WIRE 16 -1 (-2175 5125)(-2175 5725);
WIRE 16 -1 (-1875 5125)(-2175 5125);
WIRE 16 -1 (-2175 5075)(-2175 5125);
WIRE 16 -1 (-2875 5625)(-2875 5725);
WIRE 16 -1 (-2875 5725)(-2875 5800);
WIRE 16 -1 (-1875 5075)(-2175 5075);
WIRE 16 -1 (-2175 5025)(-2175 5075);
WIRE 16 -1 (-1875 5025)(-2175 5025);
WIRE 16 -1 (-7525 3175)(-8150 3175);
FORCEPROP 2 LAST SIG_NAME M_B_CPU1_ALERT_N
J 0
(-8135 3185);
DISPLAY 0.489362 (-8135 3185);
WIRE 16 -1 (-7525 3225)(-8150 3225);
FORCEPROP 2 LAST SIG_NAME M_B_CPU1_RESET_N
J 0
(-8135 3235);
DISPLAY 0.489362 (-8135 3235);
WIRE 16 -1 (-7525 3425)(-7725 3425);
WIRE 16 -1 (-7525 3375)(-7725 3375);
WIRE 16 -1 (-6125 3425)(-6325 3425);
WIRE 16 -1 (-9075 2275)(-8725 2275);
FORCEPROP 2 LAST SIG_NAME PWRGD_CHAF_CPU1
J 0
(-9110 2285);
DISPLAY 0.489362 (-9110 2285);
WIRE 16 -1 (-6125 2425)(-6325 2425);
WIRE 16 -1 (-7525 5225)(-7725 5225);
WIRE 16 -1 (-3500 4300)(-3650 4300);
WIRE 16 -1 (-3650 4350)(-3300 4350);
WIRE 16 -1 (-6125 5375)(-6325 5375);
WIRE 16 -1 (-6325 4925)(-6125 4925);
WIRE 16 -1 (-3650 4500)(-3500 4500);
WIRE 16 -1 (-3650 3450)(-3500 3450);
WIRE 16 -1 (-3650 3400)(-3300 3400);
WIRE 16 -1 (-3650 4450)(-3300 4450);
WIRE 16 -1 (-3500 4400)(-3650 4400);
WIRE 16 -1 (-3650 3200)(-3300 3200);
WIRE 16 -1 (-3500 3150)(-3650 3150);
WIRE 16 -1 (-3650 3100)(-3300 3100);
WIRE 16 -1 (-3650 4150)(-3300 4150);
WIRE 16 -1 (-3650 3050)(-3500 3050);
WIRE 16 -1 (-3650 3000)(-3300 3000);
WIRE 16 -1 (-3650 4100)(-3500 4100);
WIRE 16 -1 (-3650 4050)(-3300 4050);
WIRE 16 -1 (-3500 2950)(-3650 2950);
WIRE 16 -1 (-3650 2900)(-3300 2900);
WIRE 16 -1 (-3500 4000)(-3650 4000);
WIRE 16 -1 (-3650 3950)(-3300 3950);
WIRE 16 -1 (-3500 2850)(-3650 2850);
WIRE 16 -1 (-3650 2800)(-3300 2800);
WIRE 16 -1 (-3500 3900)(-3650 3900);
WIRE 16 -1 (-3650 3850)(-3300 3850);
WIRE 16 -1 (-3500 2750)(-3650 2750);
WIRE 16 -1 (-3650 2700)(-3300 2700);
WIRE 16 -1 (-3500 3800)(-3650 3800);
WIRE 16 -1 (-3650 3750)(-3300 3750);
WIRE 16 -1 (-3650 2650)(-3500 2650);
WIRE 16 -1 (-3650 2600)(-3300 2600);
WIRE 16 -1 (-3650 3700)(-3500 3700);
WIRE 16 -1 (-3650 3650)(-3300 3650);
WIRE 16 -1 (-3500 2550)(-3650 2550);
WIRE 16 -1 (-3650 2500)(-3300 2500);
WIRE 16 -1 (-3500 3600)(-3650 3600);
WIRE 16 -1 (-3650 3550)(-3300 3550);
WIRE 16 -1 (-3500 3250)(-3650 3250);
WIRE 16 -1 (-3650 3300)(-3300 3300);
WIRE 16 -1 (-3500 3350)(-3650 3350);
WIRE 16 -1 (-3500 4200)(-3650 4200);
WIRE 16 -1 (-3650 4250)(-3300 4250);
WIRE 16 -1 (-7525 5275)(-7725 5275);
WIRE 16 -1 (-7525 5425)(-7725 5425);
WIRE 16 -1 (-6325 5525)(-6125 5525);
WIRE 16 -1 (-6125 5425)(-6325 5425);
WIRE 16 -1 (-6125 5175)(-6325 5175);
WIRE 16 -1 (-7525 4675)(-8325 4675);
FORCEPROP 2 LAST SIG_NAME M_B_CPU1_SB_PAR
J 0
(-8275 4685);
DISPLAY 0.489362 (-8275 4685);
WIRE 16 -1 (-7525 4725)(-8325 4725);
FORCEPROP 2 LAST SIG_NAME M_B_CPU1_SA_PAR
J 0
(-8275 4735);
DISPLAY 0.489362 (-8275 4735);
WIRE 16 -1 (-7525 2125)(-8325 2125);
FORCEPROP 2 LAST SIG_NAME M_B_CPU1_SA_RSP<0>
J 0
(-8275 2135);
DISPLAY 0.489362 (-8275 2135);
WIRE 16 -1 (-6125 2325)(-6325 2325);
WIRE 16 -1 (-6125 2375)(-6325 2375);
WIRE 16 -1 (-6325 2475)(-6125 2475);
WIRE 16 -1 (-6125 2525)(-6325 2525);
WIRE 16 -1 (-6125 2575)(-6325 2575);
WIRE 16 -1 (-6125 2625)(-6325 2625);
WIRE 16 -1 (-6325 2675)(-6125 2675);
WIRE 16 -1 (-6125 2725)(-6325 2725);
WIRE 16 -1 (-6125 2775)(-6325 2775);
WIRE 16 -1 (-6125 2825)(-6325 2825);
WIRE 16 -1 (-6325 2875)(-6125 2875);
WIRE 16 -1 (-6125 2925)(-6325 2925);
WIRE 16 -1 (-6125 2975)(-6325 2975);
WIRE 16 -1 (-6125 3025)(-6325 3025);
WIRE 16 -1 (-6325 3075)(-6125 3075);
WIRE 16 -1 (-6125 3125)(-6325 3125);
WIRE 16 -1 (-6125 3175)(-6325 3175);
WIRE 16 -1 (-6125 3225)(-6325 3225);
WIRE 16 -1 (-6325 3275)(-6125 3275);
WIRE 16 -1 (-6125 3325)(-6325 3325);
WIRE 16 -1 (-6125 3375)(-6325 3375);
WIRE 16 -1 (-6325 3475)(-6125 3475);
WIRE 16 -1 (-6125 3525)(-6325 3525);
WIRE 16 -1 (-6125 3575)(-6325 3575);
WIRE 16 -1 (-6125 3625)(-6325 3625);
WIRE 16 -1 (-6125 3725)(-6325 3725);
WIRE 16 -1 (-6125 3775)(-6325 3775);
WIRE 16 -1 (-6125 3825)(-6325 3825);
WIRE 16 -1 (-6325 3875)(-6125 3875);
WIRE 16 -1 (-6125 3975)(-6325 3975);
WIRE 16 -1 (-6125 4025)(-6325 4025);
WIRE 16 -1 (-6125 4075)(-6325 4075);
WIRE 16 -1 (-6325 4125)(-6125 4125);
WIRE 16 -1 (-6125 4175)(-6325 4175);
WIRE 16 -1 (-6125 4225)(-6325 4225);
WIRE 16 -1 (-6125 4275)(-6325 4275);
WIRE 16 -1 (-6325 4325)(-6125 4325);
WIRE 16 -1 (-6125 4375)(-6325 4375);
WIRE 16 -1 (-6125 4425)(-6325 4425);
WIRE 16 -1 (-6125 4475)(-6325 4475);
WIRE 16 -1 (-6325 4525)(-6125 4525);
WIRE 16 -1 (-6125 4575)(-6325 4575);
WIRE 16 -1 (-6125 4625)(-6325 4625);
WIRE 16 -1 (-6125 4675)(-6325 4675);
WIRE 16 -1 (-6325 4725)(-6125 4725);
WIRE 16 -1 (-6125 4775)(-6325 4775);
WIRE 16 -1 (-6125 4825)(-6325 4825);
WIRE 16 -1 (-6125 4875)(-6325 4875);
WIRE 16 -1 (-6125 4975)(-6325 4975);
WIRE 16 -1 (-6125 5025)(-6325 5025);
WIRE 16 -1 (-6125 5075)(-6325 5075);
WIRE 16 -1 (-6325 5125)(-6125 5125);
WIRE 16 -1 (-6125 5225)(-6325 5225);
WIRE 16 -1 (-6125 5275)(-6325 5275);
WIRE 16 -1 (-6325 5325)(-6125 5325);
WIRE 16 -1 (-6125 5475)(-6325 5475);
WIRE 16 -1 (-7525 4425)(-8325 4425);
FORCEPROP 2 LAST SIG_NAME M_B_CPU1_SB_CS_N<1>
J 0
(-8275 4435);
DISPLAY 0.489362 (-8275 4435);
WIRE 16 -1 (-7525 4575)(-8325 4575);
FORCEPROP 2 LAST SIG_NAME M_B_CPU1_SA_CS_N<1>
J 0
(-8275 4585);
DISPLAY 0.489362 (-8275 4585);
WIRE 16 -1 (-7525 4375)(-8325 4375);
FORCEPROP 2 LAST SIG_NAME M_B_CPU1_SB_CS_N<0>
J 0
(-8275 4385);
DISPLAY 0.489362 (-8275 4385);
WIRE 16 -1 (-7525 4525)(-8325 4525);
FORCEPROP 2 LAST SIG_NAME M_B_CPU1_SA_CS_N<0>
J 0
(-8275 4535);
DISPLAY 0.489362 (-8275 4535);
WIRE 16 -1 (-7525 4275)(-8325 4275);
FORCEPROP 2 LAST SIG_NAME M_B_CPU1_CLK_DP<0>
J 0
(-8275 4285);
DISPLAY 0.489362 (-8275 4285);
WIRE 16 -1 (-7525 4225)(-8325 4225);
FORCEPROP 2 LAST SIG_NAME M_B_CPU1_CLK_DN<0>
J 0
(-8275 4235);
DISPLAY 0.489362 (-8275 4235);
WIRE 16 -1 (-7525 3325)(-7725 3325);
WIRE 16 -1 (-7525 3475)(-7725 3475);
WIRE 16 -1 (-7525 3525)(-7725 3525);
WIRE 16 -1 (-7525 3575)(-7725 3575);
WIRE 16 -1 (-7525 3625)(-7725 3625);
WIRE 16 -1 (-7525 3775)(-7725 3775);
WIRE 16 -1 (-7525 3875)(-7725 3875);
WIRE 16 -1 (-7525 3925)(-7725 3925);
WIRE 16 -1 (-7525 4025)(-7725 4025);
WIRE 16 -1 (-7525 4075)(-7725 4075);
WIRE 16 -1 (-7525 5125)(-7725 5125);
WIRE 16 -1 (-7525 5525)(-7725 5525);
WIRE 16 -1 (-7525 5075)(-7725 5075);
WIRE 16 -1 (-7525 5475)(-7725 5475);
WIRE 16 -1 (-7525 5025)(-7725 5025);
WIRE 16 -1 (-7525 4975)(-7725 4975);
WIRE 16 -1 (-7525 5375)(-7725 5375);
WIRE 16 -1 (-7525 4925)(-7725 4925);
WIRE 16 -1 (-7525 5325)(-7725 5325);
WIRE 16 -1 (-7525 4875)(-7725 4875);
WIRE 16 -1 (-7525 4825)(-7725 4825);
WIRE 16 -1 (-7525 3675)(-7725 3675);
WIRE 16 -1 (-7525 3825)(-7725 3825);
WIRE 16 -1 (-7525 3975)(-7725 3975);
WIRE 16 -1 (-7525 4125)(-7725 4125);
WIRE 16 -1 (-6475 1625)(-6475 1550);
WIRE 16 -1 (-6475 1625)(-7200 1625);
FORCEPROP 2 LAST SIG_NAME PD_CHB_CPU1_DIMM_SAA
J 0
(-7185 1635);
DISPLAY 0.489362 (-7185 1635);
DOT 1 (-8625 3450);
DOT 1 (-2175 5125);
DOT 1 (-2875 5300);
DOT 1 (-2175 4775);
DOT 1 (-2175 5075);
DOT 1 (-2175 3775);
DOT 1 (-2175 2375);
DOT 1 (-375 5075);
DOT 1 (-375 5025);
DOT 1 (-375 4975);
DOT 1 (-375 4925);
DOT 1 (-375 4825);
DOT 1 (-375 4875);
DOT 1 (-375 4775);
DOT 1 (-375 4725);
DOT 1 (-375 4675);
DOT 1 (-375 4625);
DOT 1 (-375 4575);
DOT 1 (-375 4525);
DOT 1 (-375 4475);
DOT 1 (-375 4425);
DOT 1 (-375 4375);
DOT 1 (-375 4325);
DOT 1 (-375 4275);
DOT 1 (-375 4225);
DOT 1 (-375 4175);
DOT 1 (-375 4125);
DOT 1 (-375 4075);
DOT 1 (-375 4025);
DOT 1 (-375 3975);
DOT 1 (-375 3925);
DOT 1 (-375 3875);
DOT 1 (-375 3825);
DOT 1 (-2175 4925);
DOT 1 (-2175 4825);
DOT 1 (-2175 4875);
DOT 1 (-2175 4725);
DOT 1 (-2175 4675);
DOT 1 (-2175 4625);
DOT 1 (-2175 4575);
DOT 1 (-2175 4525);
DOT 1 (-2175 4425);
DOT 1 (-2175 4475);
DOT 1 (-2175 4325);
DOT 1 (-2175 4375);
DOT 1 (-2175 4275);
DOT 1 (-2175 4225);
DOT 1 (-2175 4175);
DOT 1 (-2175 4125);
DOT 1 (-2175 4075);
DOT 1 (-2175 4025);
DOT 1 (-2175 3975);
DOT 1 (-2175 3925);
DOT 1 (-2175 3875);
DOT 1 (-2175 3825);
DOT 1 (-375 3775);
DOT 1 (-375 3675);
DOT 1 (-375 3725);
DOT 1 (-375 3625);
DOT 1 (-375 3575);
DOT 1 (-375 3525);
DOT 1 (-375 3475);
DOT 1 (-375 3425);
DOT 1 (-375 3375);
DOT 1 (-375 3325);
DOT 1 (-375 3275);
DOT 1 (-375 3175);
DOT 1 (-375 3225);
DOT 1 (-375 3125);
DOT 1 (-375 3075);
DOT 1 (-375 3025);
DOT 1 (-375 2975);
DOT 1 (-375 2925);
DOT 1 (-375 2875);
DOT 1 (-375 2775);
DOT 1 (-375 2825);
DOT 1 (-375 2725);
DOT 1 (-375 2675);
DOT 1 (-375 2625);
DOT 1 (-375 2575);
DOT 1 (-375 2525);
DOT 1 (-375 2475);
DOT 1 (-375 2425);
DOT 1 (-375 2375);
DOT 1 (-375 2325);
DOT 1 (-375 2275);
DOT 1 (-375 2225);
DOT 1 (-375 2175);
DOT 1 (-375 2125);
DOT 1 (-375 2075);
DOT 1 (-375 2025);
DOT 1 (-375 1975);
DOT 1 (-375 1875);
DOT 1 (-375 1825);
DOT 1 (-375 1775);
DOT 1 (-2175 3675);
DOT 1 (-2175 3725);
DOT 1 (-2175 3625);
DOT 1 (-2175 3575);
DOT 1 (-2175 3525);
DOT 1 (-2175 3425);
DOT 1 (-2175 3475);
DOT 1 (-2175 3375);
DOT 1 (-2175 3325);
DOT 1 (-2175 3275);
DOT 1 (-2175 3225);
DOT 1 (-2175 3175);
DOT 1 (-2175 3125);
DOT 1 (-2175 3075);
DOT 1 (-2175 3025);
DOT 1 (-2175 2975);
DOT 1 (-2175 2925);
DOT 1 (-2175 2875);
DOT 1 (-2175 2775);
DOT 1 (-2175 2825);
DOT 1 (-2175 2725);
DOT 1 (-2175 2675);
DOT 1 (-2175 2625);
DOT 1 (-2175 2525);
DOT 1 (-2175 2575);
DOT 1 (-2175 2475);
DOT 1 (-2175 2425);
DOT 1 (-2175 2325);
DOT 1 (-2175 2275);
DOT 1 (-2175 2225);
DOT 1 (-2175 2175);
DOT 1 (-2175 2125);
DOT 1 (-2175 2075);
DOT 1 (-2175 2025);
DOT 1 (-2175 1975);
DOT 1 (-2175 1925);
DOT 1 (-2175 1875);
DOT 1 (-8500 2275);
DOT 1 (-2875 5725);
DOT 1 (-2300 5725);
QUIT
